G04 ================== begin FILE IDENTIFICATION RECORD ==================*
G04 Layout Name:  D:/<user>/Wistron_project/16316-1/gbr-0621/16316-1.brd*
G04 Film Name:    L5VCC*
G04 File Format:  Gerber RS274X*
G04 File Origin:  Cadence Allegro 16.5-S056*
G04 Origin Date:  Wed Jun 21 09:32:10 2017*
G04 *
G04 Layer:  VIA CLASS/L5VCC*
G04 Layer:  PIN/L5VCC*
G04 Layer:  PACKAGE GEOMETRY/PWRVCC*
G04 Layer:  ETCH/L5VCC*
G04 Layer:  DRAWING FORMAT/LAYER_PCB_STORY*
G04 Layer:  DRAWING FORMAT/LAYER_L5VCC*
G04 *
G04 Offset:    (0.00 0.00)*
G04 Mirror:    No*
G04 Mode:      Negative*
G04 Rotation:  0*
G04 FullContactRelief:  No*
G04 UndefLineWidth:     6.00*
G04 ================== end FILE IDENTIFICATION RECORD ====================*
%FSLAX35Y35*MOIN*%
%IR0*IPPOS*OFA0.00000B0.00000*MIA0B0*SFA1.00000B1.00000*%
%ADD14C,.03*%
%ADD15C,.04*%
%ADD16C,.032*%
%ADD35C,.034*%
%ADD29C,.043*%
%ADD24C,.07*%
%ADD22C,.036*%
%ADD18C,.09*%
%ADD32C,.028*%
%ADD25C,.058*%
%AMMACRO23*
4,1,15,.00398,.00044,
.003999,.000208,
.004004,-.000025,
.003996,-.000258,
.00398,-.00044,
.00483,-.00129,
.004897,-.001007,
.004947,-.000721,
.004981,-.000432,
.004997,-.000141,
.004997,.000149,
.00498,.00044,
.004946,.000729,
.004895,.001015,
.00483,.00129,
.00398,.00044,
90.*
4,1,15,.00044,-.00398,
.000208,-.003999,
-.000025,-.004004,
-.000258,-.003996,
-.00044,-.00398,
-.00129,-.00483,
-.001007,-.004897,
-.000721,-.004947,
-.000432,-.004981,
-.000141,-.004997,
.000149,-.004997,
.00044,-.00498,
.000729,-.004946,
.001015,-.004895,
.00129,-.00483,
.00044,-.00398,
90.*
4,1,15,-.00398,-.00044,
-.003999,-.000208,
-.004004,.000025,
-.003996,.000258,
-.00398,.00044,
-.00483,.00129,
-.004897,.001007,
-.004947,.000721,
-.004981,.000432,
-.004997,.000141,
-.004997,-.000149,
-.00498,-.00044,
-.004946,-.000729,
-.004895,-.001015,
-.00483,-.00129,
-.00398,-.00044,
90.*
4,1,15,-.00044,.00398,
-.000208,.003999,
.000025,.004004,
.000258,.003996,
.00044,.00398,
.00129,.00483,
.001007,.004897,
.000721,.004947,
.000432,.004981,
.000141,.004997,
-.000149,.004997,
-.00044,.00498,
-.000729,.004946,
-.001015,.004895,
-.00129,.00483,
-.00044,.00398,
90.*
%
%ADD23MACRO23*%
%AMMACRO26*
4,1,15,-.00398,.00044,
-.003999,.000208,
-.004004,-.000025,
-.003996,-.000258,
-.00398,-.00044,
-.00483,-.00129,
-.004897,-.001007,
-.004947,-.000721,
-.004981,-.000432,
-.004997,-.000141,
-.004997,.000149,
-.00498,.00044,
-.004946,.000729,
-.004895,.001015,
-.00483,.00129,
-.00398,.00044,
90.*
4,1,15,-.00044,-.00398,
-.000208,-.003999,
.000025,-.004004,
.000258,-.003996,
.00044,-.00398,
.00129,-.00483,
.001007,-.004897,
.000721,-.004947,
.000432,-.004981,
.000141,-.004997,
-.000149,-.004997,
-.00044,-.00498,
-.000729,-.004946,
-.001015,-.004895,
-.00129,-.00483,
-.00044,-.00398,
90.*
4,1,15,.00398,-.00044,
.003999,-.000208,
.004004,.000025,
.003996,.000258,
.00398,.00044,
.00483,.00129,
.004897,.001007,
.004947,.000721,
.004981,.000432,
.004997,.000141,
.004997,-.000149,
.00498,-.00044,
.004946,-.000729,
.004895,-.001015,
.00483,-.00129,
.00398,-.00044,
90.*
4,1,15,.00044,.00398,
.000208,.003999,
-.000025,.004004,
-.000258,.003996,
-.00044,.00398,
-.00129,.00483,
-.001007,.004897,
-.000721,.004947,
-.000432,.004981,
-.000141,.004997,
.000149,.004997,
.00044,.00498,
.000729,.004946,
.001015,.004895,
.00129,.00483,
.00044,.00398,
90.*
%
%ADD26MACRO26*%
%AMMACRO11*
4,1,15,.00398,.00044,
.003999,.000208,
.004004,-.000025,
.003996,-.000258,
.00398,-.00044,
.00483,-.00129,
.004897,-.001007,
.004947,-.000721,
.004981,-.000432,
.004997,-.000141,
.004997,.000149,
.00498,.00044,
.004946,.000729,
.004895,.001015,
.00483,.00129,
.00398,.00044,
0.0*
4,1,15,.00044,-.00398,
.000208,-.003999,
-.000025,-.004004,
-.000258,-.003996,
-.00044,-.00398,
-.00129,-.00483,
-.001007,-.004897,
-.000721,-.004947,
-.000432,-.004981,
-.000141,-.004997,
.000149,-.004997,
.00044,-.00498,
.000729,-.004946,
.001015,-.004895,
.00129,-.00483,
.00044,-.00398,
0.0*
4,1,15,-.00398,-.00044,
-.003999,-.000208,
-.004004,.000025,
-.003996,.000258,
-.00398,.00044,
-.00483,.00129,
-.004897,.001007,
-.004947,.000721,
-.004981,.000432,
-.004997,.000141,
-.004997,-.000149,
-.00498,-.00044,
-.004946,-.000729,
-.004895,-.001015,
-.00483,-.00129,
-.00398,-.00044,
0.0*
4,1,15,-.00044,.00398,
-.000208,.003999,
.000025,.004004,
.000258,.003996,
.00044,.00398,
.00129,.00483,
.001007,.004897,
.000721,.004947,
.000432,.004981,
.000141,.004997,
-.000149,.004997,
-.00044,.00498,
-.000729,.004946,
-.001015,.004895,
-.00129,.00483,
-.00044,.00398,
0.0*
%
%ADD11MACRO11*%
%AMMACRO27*
4,1,15,-.00398,.00044,
-.003999,.000208,
-.004004,-.000025,
-.003996,-.000258,
-.00398,-.00044,
-.00483,-.00129,
-.004897,-.001007,
-.004947,-.000721,
-.004981,-.000432,
-.004997,-.000141,
-.004997,.000149,
-.00498,.00044,
-.004946,.000729,
-.004895,.001015,
-.00483,.00129,
-.00398,.00044,
0.0*
4,1,15,-.00044,-.00398,
-.000208,-.003999,
.000025,-.004004,
.000258,-.003996,
.00044,-.00398,
.00129,-.00483,
.001007,-.004897,
.000721,-.004947,
.000432,-.004981,
.000141,-.004997,
-.000149,-.004997,
-.00044,-.00498,
-.000729,-.004946,
-.001015,-.004895,
-.00129,-.00483,
-.00044,-.00398,
0.0*
4,1,15,.00398,-.00044,
.003999,-.000208,
.004004,.000025,
.003996,.000258,
.00398,.00044,
.00483,.00129,
.004897,.001007,
.004947,.000721,
.004981,.000432,
.004997,.000141,
.004997,-.000149,
.00498,-.00044,
.004946,-.000729,
.004895,-.001015,
.00483,-.00129,
.00398,-.00044,
0.0*
4,1,15,.00044,.00398,
.000208,.003999,
-.000025,.004004,
-.000258,.003996,
-.00044,.00398,
-.00129,.00483,
-.001007,.004897,
-.000721,.004947,
-.000432,.004981,
-.000141,.004997,
.000149,.004997,
.00044,.00498,
.000729,.004946,
.001015,.004895,
.00129,.00483,
.00044,.00398,
0.0*
%
%ADD27MACRO27*%
%ADD19C,.111*%
%ADD20C,.122*%
%ADD10C,.114*%
%ADD31C,.115*%
%ADD21C,.125*%
%ADD30C,.147*%
%ADD17C,.186*%
%ADD28C,.178*%
%AMMACRO34*
4,1,15,.00398,.00044,
.003999,.000208,
.004004,-.000025,
.003996,-.000258,
.00398,-.00044,
.00483,-.00129,
.004897,-.001007,
.004947,-.000721,
.004981,-.000432,
.004997,-.000141,
.004997,.000149,
.00498,.00044,
.004946,.000729,
.004895,.001015,
.00483,.00129,
.00398,.00044,
315.*
4,1,15,.00044,-.00398,
.000208,-.003999,
-.000025,-.004004,
-.000258,-.003996,
-.00044,-.00398,
-.00129,-.00483,
-.001007,-.004897,
-.000721,-.004947,
-.000432,-.004981,
-.000141,-.004997,
.000149,-.004997,
.00044,-.00498,
.000729,-.004946,
.001015,-.004895,
.00129,-.00483,
.00044,-.00398,
315.*
4,1,15,-.00398,-.00044,
-.003999,-.000208,
-.004004,.000025,
-.003996,.000258,
-.00398,.00044,
-.00483,.00129,
-.004897,.001007,
-.004947,.000721,
-.004981,.000432,
-.004997,.000141,
-.004997,-.000149,
-.00498,-.00044,
-.004946,-.000729,
-.004895,-.001015,
-.00483,-.00129,
-.00398,-.00044,
315.*
4,1,15,-.00044,.00398,
-.000208,.003999,
.000025,.004004,
.000258,.003996,
.00044,.00398,
.00129,.00483,
.001007,.004897,
.000721,.004947,
.000432,.004981,
.000141,.004997,
-.000149,.004997,
-.00044,.00498,
-.000729,.004946,
-.001015,.004895,
-.00129,.00483,
-.00044,.00398,
315.*
%
%ADD34MACRO34*%
%AMMACRO33*
4,1,15,.00398,.00044,
.003999,.000208,
.004004,-.000025,
.003996,-.000258,
.00398,-.00044,
.00483,-.00129,
.004897,-.001007,
.004947,-.000721,
.004981,-.000432,
.004997,-.000141,
.004997,.000149,
.00498,.00044,
.004946,.000729,
.004895,.001015,
.00483,.00129,
.00398,.00044,
225.*
4,1,15,.00044,-.00398,
.000208,-.003999,
-.000025,-.004004,
-.000258,-.003996,
-.00044,-.00398,
-.00129,-.00483,
-.001007,-.004897,
-.000721,-.004947,
-.000432,-.004981,
-.000141,-.004997,
.000149,-.004997,
.00044,-.00498,
.000729,-.004946,
.001015,-.004895,
.00129,-.00483,
.00044,-.00398,
225.*
4,1,15,-.00398,-.00044,
-.003999,-.000208,
-.004004,.000025,
-.003996,.000258,
-.00398,.00044,
-.00483,.00129,
-.004897,.001007,
-.004947,.000721,
-.004981,.000432,
-.004997,.000141,
-.004997,-.000149,
-.00498,-.00044,
-.004946,-.000729,
-.004895,-.001015,
-.00483,-.00129,
-.00398,-.00044,
225.*
4,1,15,-.00044,.00398,
-.000208,.003999,
.000025,.004004,
.000258,.003996,
.00044,.00398,
.00129,.00483,
.001007,.004897,
.000721,.004947,
.000432,.004981,
.000141,.004997,
-.000149,.004997,
-.00044,.00498,
-.000729,.004946,
-.001015,.004895,
-.00129,.00483,
-.00044,.00398,
225.*
%
%ADD33MACRO33*%
%AMMACRO13*
4,1,15,.00398,.00044,
.003999,.000208,
.004004,-.000025,
.003996,-.000258,
.00398,-.00044,
.00483,-.00129,
.004897,-.001007,
.004947,-.000721,
.004981,-.000432,
.004997,-.000141,
.004997,.000149,
.00498,.00044,
.004946,.000729,
.004895,.001015,
.00483,.00129,
.00398,.00044,
180.*
4,1,15,.00044,-.00398,
.000208,-.003999,
-.000025,-.004004,
-.000258,-.003996,
-.00044,-.00398,
-.00129,-.00483,
-.001007,-.004897,
-.000721,-.004947,
-.000432,-.004981,
-.000141,-.004997,
.000149,-.004997,
.00044,-.00498,
.000729,-.004946,
.001015,-.004895,
.00129,-.00483,
.00044,-.00398,
180.*
4,1,15,-.00398,-.00044,
-.003999,-.000208,
-.004004,.000025,
-.003996,.000258,
-.00398,.00044,
-.00483,.00129,
-.004897,.001007,
-.004947,.000721,
-.004981,.000432,
-.004997,.000141,
-.004997,-.000149,
-.00498,-.00044,
-.004946,-.000729,
-.004895,-.001015,
-.00483,-.00129,
-.00398,-.00044,
180.*
4,1,15,-.00044,.00398,
-.000208,.003999,
.000025,.004004,
.000258,.003996,
.00044,.00398,
.00129,.00483,
.001007,.004897,
.000721,.004947,
.000432,.004981,
.000141,.004997,
-.000149,.004997,
-.00044,.00498,
-.000729,.004946,
-.001015,.004895,
-.00129,.00483,
-.00044,.00398,
180.*
%
%ADD13MACRO13*%
%AMMACRO12*
4,1,15,.00398,.00044,
.003999,.000208,
.004004,-.000025,
.003996,-.000258,
.00398,-.00044,
.00483,-.00129,
.004897,-.001007,
.004947,-.000721,
.004981,-.000432,
.004997,-.000141,
.004997,.000149,
.00498,.00044,
.004946,.000729,
.004895,.001015,
.00483,.00129,
.00398,.00044,
270.*
4,1,15,.00044,-.00398,
.000208,-.003999,
-.000025,-.004004,
-.000258,-.003996,
-.00044,-.00398,
-.00129,-.00483,
-.001007,-.004897,
-.000721,-.004947,
-.000432,-.004981,
-.000141,-.004997,
.000149,-.004997,
.00044,-.00498,
.000729,-.004946,
.001015,-.004895,
.00129,-.00483,
.00044,-.00398,
270.*
4,1,15,-.00398,-.00044,
-.003999,-.000208,
-.004004,.000025,
-.003996,.000258,
-.00398,.00044,
-.00483,.00129,
-.004897,.001007,
-.004947,.000721,
-.004981,.000432,
-.004997,.000141,
-.004997,-.000149,
-.00498,-.00044,
-.004946,-.000729,
-.004895,-.001015,
-.00483,-.00129,
-.00398,-.00044,
270.*
4,1,15,-.00044,.00398,
-.000208,.003999,
.000025,.004004,
.000258,.003996,
.00044,.00398,
.00129,.00483,
.001007,.004897,
.000721,.004947,
.000432,.004981,
.000141,.004997,
-.000149,.004997,
-.00044,.00498,
-.000729,.004946,
-.001015,.004895,
-.00129,.00483,
-.00044,.00398,
270.*
%
%ADD12MACRO12*%
%AMMACRO37*
4,1,15,-.00398,.00044,
-.003999,.000208,
-.004004,-.000025,
-.003996,-.000258,
-.00398,-.00044,
-.00483,-.00129,
-.004897,-.001007,
-.004947,-.000721,
-.004981,-.000432,
-.004997,-.000141,
-.004997,.000149,
-.00498,.00044,
-.004946,.000729,
-.004895,.001015,
-.00483,.00129,
-.00398,.00044,
270.*
4,1,15,-.00044,-.00398,
-.000208,-.003999,
.000025,-.004004,
.000258,-.003996,
.00044,-.00398,
.00129,-.00483,
.001007,-.004897,
.000721,-.004947,
.000432,-.004981,
.000141,-.004997,
-.000149,-.004997,
-.00044,-.00498,
-.000729,-.004946,
-.001015,-.004895,
-.00129,-.00483,
-.00044,-.00398,
270.*
4,1,15,.00398,-.00044,
.003999,-.000208,
.004004,.000025,
.003996,.000258,
.00398,.00044,
.00483,.00129,
.004897,.001007,
.004947,.000721,
.004981,.000432,
.004997,.000141,
.004997,-.000149,
.00498,-.00044,
.004946,-.000729,
.004895,-.001015,
.00483,-.00129,
.00398,-.00044,
270.*
4,1,15,.00044,.00398,
.000208,.003999,
-.000025,.004004,
-.000258,.003996,
-.00044,.00398,
-.00129,.00483,
-.001007,.004897,
-.000721,.004947,
-.000432,.004981,
-.000141,.004997,
.000149,.004997,
.00044,.00498,
.000729,.004946,
.001015,.004895,
.00129,.00483,
.00044,.00398,
270.*
%
%ADD37MACRO37*%
%AMMACRO36*
4,1,15,.00398,.00044,
.003999,.000208,
.004004,-.000025,
.003996,-.000258,
.00398,-.00044,
.00483,-.00129,
.004897,-.001007,
.004947,-.000721,
.004981,-.000432,
.004997,-.000141,
.004997,.000149,
.00498,.00044,
.004946,.000729,
.004895,.001015,
.00483,.00129,
.00398,.00044,
282.*
4,1,15,.00044,-.00398,
.000208,-.003999,
-.000025,-.004004,
-.000258,-.003996,
-.00044,-.00398,
-.00129,-.00483,
-.001007,-.004897,
-.000721,-.004947,
-.000432,-.004981,
-.000141,-.004997,
.000149,-.004997,
.00044,-.00498,
.000729,-.004946,
.001015,-.004895,
.00129,-.00483,
.00044,-.00398,
282.*
4,1,15,-.00398,-.00044,
-.003999,-.000208,
-.004004,.000025,
-.003996,.000258,
-.00398,.00044,
-.00483,.00129,
-.004897,.001007,
-.004947,.000721,
-.004981,.000432,
-.004997,.000141,
-.004997,-.000149,
-.00498,-.00044,
-.004946,-.000729,
-.004895,-.001015,
-.00483,-.00129,
-.00398,-.00044,
282.*
4,1,15,-.00044,.00398,
-.000208,.003999,
.000025,.004004,
.000258,.003996,
.00044,.00398,
.00129,.00483,
.001007,.004897,
.000721,.004947,
.000432,.004981,
.000141,.004997,
-.000149,.004997,
-.00044,.00498,
-.000729,.004946,
-.001015,.004895,
-.00129,.00483,
-.00044,.00398,
282.*
%
%ADD36MACRO36*%
%ADD38C,.02*%
%ADD39C,.006*%
%ADD43C,.06604*%
%ADD40C,.11004*%
%ADD47C,.11104*%
%ADD42C,.11804*%
%ADD46C,.37405*%
%ADD45C,.23626*%
%ADD48C,.37406*%
%ADD44C,.23627*%
%ADD41C,.27563*%
G75*
%LPD*%
G75*
G36*
G01X-6000Y-6000D02*
X832772D01*
Y576866D01*
X-6000D01*
Y-6000D01*
G37*
%LPC*%
G75*
G36*
G01X690370Y326830D02*
X689189Y325650D01*
X666820D01*
G03X662642I-2089J-1551D01*
G01X660397D01*
X660381Y325652D01*
G03X659573I-404J-2570D01*
G01X659557Y325650D01*
X617389D01*
X612250Y320511D01*
Y103689D01*
X616262Y99677D01*
X701438D01*
X710450Y108689D01*
Y135489D01*
X711411Y136450D01*
X732511D01*
X735650Y139589D01*
Y250589D01*
X761350Y276289D01*
Y288589D01*
X762811Y290050D01*
X775011D01*
X793850Y308889D01*
Y406250D01*
X820546D01*
X821772Y405024D01*
Y7874D01*
G02X818898Y5000I-2874J0D01*
G01X7874D01*
G02X5000Y7874I0J2874D01*
G01Y562992D01*
G02X7874Y565866I2874J0D01*
G01X177266D01*
G02X177665Y565453I-1J-400D01*
G03X179250Y562971I2601J-86D01*
G01Y456958D01*
X178309Y456017D01*
X93865D01*
X87733Y449885D01*
Y378844D01*
X87730Y378826D01*
G03Y378026I2165J-400D01*
G01X87733Y378008D01*
Y353483D01*
X86700Y352450D01*
X31289D01*
X23850Y345011D01*
Y318689D01*
X36289Y306250D01*
X91789D01*
X98650Y299389D01*
Y181189D01*
X120450Y159389D01*
Y98689D01*
X151189Y67950D01*
X233089D01*
X235950Y65089D01*
Y54689D01*
X241798Y48841D01*
X262713D01*
X265250Y51378D01*
Y78711D01*
X251311Y92650D01*
X158311D01*
X138650Y112311D01*
Y177611D01*
X118250Y198011D01*
Y298689D01*
X123811Y304250D01*
X197889D01*
X199250Y302889D01*
Y217689D01*
X232950Y183989D01*
Y134540D01*
G03X233197Y133943I850J2D01*
G03X233199Y133941I531J529D01*
G01X235289Y131850D01*
X320726D01*
X320740Y131848D01*
G03X321362I311J2180D01*
G01X321376Y131850D01*
X334889D01*
X348489Y118250D01*
X561189D01*
X562650Y116789D01*
Y101464D01*
X593381Y70733D01*
Y16025D01*
X598590Y10816D01*
X661585D01*
X664384Y13615D01*
Y20500D01*
X658460Y26424D01*
X612411D01*
X610281Y28554D01*
Y81250D01*
X580950Y110581D01*
Y136211D01*
X576750Y140411D01*
Y216589D01*
X583950Y223789D01*
Y303689D01*
X595150Y314889D01*
Y340089D01*
X597411Y342350D01*
X613311D01*
X645450Y374489D01*
Y389689D01*
X646611Y390850D01*
X675789D01*
X690450Y376189D01*
Y326900D01*
G03X690370Y326830I452J-598D01*
G37*
G36*
G01X635399Y366560D02*
X612689Y343850D01*
X596789D01*
X593650Y340711D01*
Y315511D01*
X582450Y304311D01*
Y224411D01*
X575250Y217211D01*
Y139789D01*
X579450Y135589D01*
Y109959D01*
X608781Y80628D01*
Y27932D01*
X611789Y24924D01*
X657838D01*
X662884Y19878D01*
Y14237D01*
X660963Y12316D01*
X599212D01*
X594881Y16647D01*
Y71355D01*
X564150Y102086D01*
Y183111D01*
X560350Y186911D01*
Y300711D01*
X555311Y305750D01*
X491353D01*
X489373Y303770D01*
Y287574D01*
X481550Y279751D01*
Y240111D01*
X480389Y238950D01*
X428809D01*
X413309Y223450D01*
X392452D01*
X385450Y230452D01*
Y255589D01*
X387011Y257150D01*
X431989D01*
X436389Y252750D01*
X465111D01*
X467850Y255489D01*
Y280311D01*
X466145Y282016D01*
X422174D01*
X419950Y284240D01*
Y312359D01*
X418929Y313380D01*
X416975D01*
X415985Y314370D01*
Y316292D01*
X414727Y317550D01*
X388211D01*
X387211Y318550D01*
X379790D01*
X375223Y313983D01*
X342975D01*
X338408Y318550D01*
X330876D01*
G03X327852I-1512J-1601D01*
G01X205589D01*
X199251Y312212D01*
Y307212D01*
X197789Y305750D01*
X123189D01*
X116750Y299311D01*
Y197389D01*
X137150Y176989D01*
Y111689D01*
X157689Y91150D01*
X250689D01*
X263750Y78089D01*
Y52000D01*
X262091Y50341D01*
X242420D01*
X237450Y55311D01*
Y65711D01*
X233711Y69450D01*
X151811D01*
X121950Y99311D01*
Y160011D01*
X100150Y181811D01*
Y300011D01*
X92411Y307750D01*
X36911D01*
X25350Y319311D01*
Y344389D01*
X31911Y350950D01*
X269711D01*
X273111Y354350D01*
X302968D01*
X303005Y354196D01*
G03X307289I2142J510D01*
G01X307326Y354350D01*
X451111D01*
X472522Y375761D01*
X519979D01*
G02X520356Y375228I0J-400D01*
G03X542636I11140J-3929D01*
G02X543013Y375761I377J133D01*
G01X560822D01*
X586611Y401550D01*
X633689D01*
X641083Y394156D01*
G03X641656Y393583I1817J1244D01*
G01X643950Y391289D01*
Y375111D01*
X636840Y368001D01*
X636796Y367986D01*
G03X635414Y366604I704J-2086D01*
G01X635399Y366560D01*
G37*
G36*
G01X760911Y291550D02*
X758450Y294011D01*
Y374211D01*
X747911Y384750D01*
X726989D01*
X719489Y377250D01*
X691511D01*
X676411Y392350D01*
X645011D01*
X634311Y403050D01*
X585989D01*
X560200Y377261D01*
X541694D01*
G03X521298I-10198J-5961D01*
G01X471900D01*
X450489Y355850D01*
X322976D01*
X322956Y355854D01*
G03X322044I-456J-2154D01*
G01X322024Y355850D01*
X307029D01*
G03X303265I-1882J-1144D01*
G01X272489D01*
X269089Y352450D01*
X199835D01*
G03X195601I-2117J-1513D01*
G01X90268D01*
X89233Y353485D01*
Y449263D01*
X94487Y454517D01*
X178307D01*
X179250Y453574D01*
Y417696D01*
X183968Y412978D01*
X329461D01*
X335948Y406491D01*
G03X338922Y403272I1645J-1464D01*
G01X339061Y403378D01*
X357689Y384750D01*
X438811D01*
X452311Y398250D01*
X504419D01*
X539119Y432950D01*
X603689D01*
X614289Y422350D01*
X641689D01*
X652089Y411950D01*
X703451D01*
X703475Y411944D01*
G03X704755I640J2522D01*
G01X704779Y411950D01*
X787089D01*
X792350Y406689D01*
Y309511D01*
X774389Y291550D01*
X760911D01*
G37*
G36*
G01X538497Y434450D02*
X503797Y399750D01*
X451689D01*
X438189Y386250D01*
X358311D01*
X339782Y404779D01*
X339788Y404870D01*
G03X337435Y407223I-2196J157D01*
G01X337344Y407217D01*
X330083Y414478D01*
X184590D01*
X180750Y418318D01*
Y562805D01*
X180901Y562843D01*
G03X182867Y565453I-635J2523D01*
G02X183266Y565866I400J13D01*
G01X326783D01*
G02X329656Y562992I-1J-2874D01*
G01Y520720D01*
G03X350441Y496345I24685J0D01*
G01X383461Y491063D01*
X443310D01*
X476350Y496348D01*
G03X497136Y520723I-3899J24375D01*
G01Y562992D01*
G02X500010Y565866I2874J0D01*
G01X818898D01*
G02X821772Y562992I0J-2874D01*
G01Y408945D01*
G03X821626Y408831I385J-643D01*
G01X820544Y407750D01*
X793411D01*
X787711Y413450D01*
X652711D01*
X642311Y423850D01*
X614911D01*
X604311Y434450D01*
X538497D01*
G37*
G36*
G01X234202Y184859D02*
X200750Y218311D01*
Y304688D01*
X200751Y304689D01*
Y311590D01*
X206211Y317050D01*
X337786D01*
X342353Y312483D01*
X375845D01*
X380412Y317050D01*
X386589D01*
X387589Y316050D01*
X414105D01*
X414485Y315670D01*
Y313748D01*
X416353Y311880D01*
X418307D01*
X418450Y311737D01*
Y283618D01*
X421552Y280516D01*
X465523D01*
X466350Y279689D01*
Y256111D01*
X464489Y254250D01*
X437011D01*
X432611Y258650D01*
X386389D01*
X383950Y256211D01*
Y245021D01*
X290460D01*
X284150Y238711D01*
Y134711D01*
X282789Y133350D01*
X235911D01*
X234450Y134811D01*
Y184259D01*
G03Y184262I-750J2D01*
G03X234202Y184859I-850J-3D01*
G37*
G36*
G01X349111Y119750D02*
X335511Y133350D01*
X287011D01*
X285650Y134711D01*
Y238089D01*
X291082Y243521D01*
X383950D01*
Y229830D01*
X391830Y221950D01*
X396181D01*
G02X396503Y221312I1J-400D01*
G03X396226Y220474I1135J-840D01*
G01Y216536D01*
G03X399050I1412J0D01*
G01Y220473D01*
G03X398773Y221312I-1412J-1D01*
G02X399095Y221950I321J238D01*
G01X400118D01*
G02X400440Y221312I1J-400D01*
G03X400164Y220474I1135J-838D01*
G01Y216536D01*
G03X402986I1411J0D01*
G01Y220473D01*
G03X402710Y221312I-1411J1D01*
G02X403032Y221950I321J238D01*
G01X404055D01*
G02X404377Y221312I1J-400D01*
G03X404100Y220474I1135J-840D01*
G01Y216536D01*
G03X406924I1412J0D01*
G01Y220473D01*
G03X406647Y221312I-1412J-1D01*
G02X406969Y221950I321J238D01*
G01X407992D01*
G02X408314Y221312I1J-400D01*
G03X408038Y220474I1135J-838D01*
G01Y216536D01*
G03X410860I1411J0D01*
G01Y220473D01*
G03X410584Y221312I-1411J1D01*
G02X410906Y221950I321J238D01*
G01X411929D01*
G02X412251Y221312I1J-400D01*
G03X411974Y220474I1135J-840D01*
G01Y216536D01*
G03X414798I1412J0D01*
G01Y220473D01*
G03X414231Y221604I-1412J0D01*
G02X414188Y222207I240J320D01*
G01X429431Y237450D01*
X481011D01*
X482801Y239241D01*
G03X482803Y239243I-529J531D01*
G03X483050Y239840I-603J599D01*
G01Y279129D01*
X490873Y286952D01*
Y303148D01*
X491975Y304250D01*
X494392D01*
G02X494761Y303695I0J-400D01*
G03X496062Y301738I1302J-545D01*
G01X500000D01*
G03X501302Y303695I0J1412D01*
G02X501671Y304250I369J155D01*
G01X554689D01*
X558850Y300089D01*
Y186289D01*
X562650Y182489D01*
Y121211D01*
X561189Y119750D01*
X349111D01*
G37*
G36*
G01X616884Y101177D02*
X613750Y104311D01*
Y319889D01*
X618011Y324150D01*
X689389D01*
X690450Y323089D01*
Y294611D01*
X648850Y253011D01*
Y162440D01*
G03X649097Y161843I850J2D01*
G03X649099Y161841I531J529D01*
G01X651089Y159850D01*
X657289D01*
X658250Y158889D01*
Y137989D01*
X659541Y136698D01*
G03X660138Y136450I600J602D01*
G03X660141I2J750D01*
G01X707989D01*
X708950Y135489D01*
Y109311D01*
X700816Y101177D01*
X616884D01*
G37*
G36*
G01X756950Y373589D02*
Y293389D01*
X759850Y290489D01*
Y276911D01*
X734150Y251211D01*
Y140211D01*
X731889Y137950D01*
X660411D01*
X659750Y138611D01*
Y159511D01*
X657911Y161350D01*
X651711D01*
X650350Y162711D01*
Y252389D01*
X691950Y293989D01*
Y374489D01*
X693211Y375750D01*
X720111D01*
X727611Y383250D01*
X747289D01*
X756950Y373589D01*
G37*
%LPD*%
G75*
G36*
G01X703902Y91010D02*
G02X700880I-1511J0D01*
G01Y94511D01*
G02X703902Y94510I1511J-1D01*
G01Y91010D01*
G37*
G36*
G01X711890Y92899D02*
G02X708866I-1512J0D01*
G01Y96400D01*
G02X711890Y96399I1512J-1D01*
G01Y92899D01*
G37*
G36*
G01X710872Y29134D02*
G02X706450I-2211J0D01*
G01Y34647D01*
G02X710872Y34646I2211J-1D01*
G01Y29134D01*
G37*
G36*
G01X760478Y10237D02*
G02X756056I-2211J0D01*
G01Y15749D01*
G02X760478Y15748I2211J-1D01*
G01Y10237D01*
G37*
G36*
G01X753392Y14961D02*
G02X748970I-2211J0D01*
G01Y20474D01*
G02X753392Y20473I2211J-1D01*
G01Y14961D01*
G37*
G36*
G01X746306Y10237D02*
G02X741882I-2212J0D01*
G01Y15749D01*
G02X746306Y15748I2212J-1D01*
G01Y10237D01*
G37*
G36*
G01X739218Y14961D02*
G02X734796I-2211J0D01*
G01Y20474D01*
G02X739218Y20473I2211J-1D01*
G01Y14961D01*
G37*
G36*
G01X732132Y10237D02*
G02X727710I-2211J0D01*
G01Y15749D01*
G02X732132Y15748I2211J-1D01*
G01Y10237D01*
G37*
G36*
G01X725046Y14961D02*
G02X720622I-2212J0D01*
G01Y20474D01*
G02X725046Y20473I2212J-1D01*
G01Y14961D01*
G37*
G36*
G01X717960Y10237D02*
G02X713536I-2212J0D01*
G01Y15749D01*
G02X717960Y15748I2212J-1D01*
G01Y10237D01*
G37*
G36*
G01X710872Y14961D02*
G02X706450I-2211J0D01*
G01Y20474D01*
G02X710872Y20473I2211J-1D01*
G01Y14961D01*
G37*
G36*
G01X732132Y38583D02*
G02X727710I-2211J0D01*
G01Y44096D01*
G02X732132Y44095I2211J-1D01*
G01Y38583D01*
G37*
G36*
G01X739218Y43307D02*
G02X734796I-2211J0D01*
G01Y48820D01*
G02X739218Y48819I2211J-1D01*
G01Y43307D01*
G37*
G36*
G01X746306Y38583D02*
G02X741882I-2212J0D01*
G01Y44096D01*
G02X746306Y44095I2212J-1D01*
G01Y38583D01*
G37*
G36*
G01X760478D02*
G02X756056I-2211J0D01*
G01Y44096D01*
G02X760478Y44095I2211J-1D01*
G01Y38583D01*
G37*
G36*
G01X725046Y43307D02*
G02X720622I-2212J0D01*
G01Y48820D01*
G02X725046Y48819I2212J-1D01*
G01Y43307D01*
G37*
G36*
G01X717960Y38583D02*
G02X713536I-2212J0D01*
G01Y44096D01*
G02X717960Y44095I2212J-1D01*
G01Y38583D01*
G37*
G36*
G01X753392Y43307D02*
G02X748970I-2211J0D01*
G01Y48820D01*
G02X753392Y48819I2211J-1D01*
G01Y43307D01*
G37*
G36*
G01X710872D02*
G02X706450I-2211J0D01*
G01Y48820D01*
G02X710872Y48819I2211J-1D01*
G01Y43307D01*
G37*
G36*
G01X655548Y91208D02*
G02X652526I-1511J0D01*
G01Y94709D01*
G02X655548Y94708I1511J-1D01*
G01Y91208D01*
G37*
G36*
G01X663558Y91039D02*
G02X660536I-1511J0D01*
G01Y94540D01*
G02X663558Y94539I1511J-1D01*
G01Y91039D01*
G37*
G36*
G01X671658Y91005D02*
G02X668634I-1512J0D01*
G01Y94506D01*
G02X671658Y94505I1512J-1D01*
G01Y91005D01*
G37*
G36*
G01X679736Y90996D02*
G02X676714I-1511J0D01*
G01Y94497D01*
G02X679736Y94496I1511J-1D01*
G01Y90996D01*
G37*
G36*
G01X687790Y90994D02*
G02X684768I-1511J0D01*
G01Y94495D01*
G02X687790Y94494I1511J-1D01*
G01Y90994D01*
G37*
G36*
G01X695876Y90958D02*
G02X692854I-1511J0D01*
G01Y94459D01*
G02X695876Y94458I1511J-1D01*
G01Y90958D01*
G37*
G36*
G01X578187Y186887D02*
G02X581711Y187635I1762J374D01*
G01X582637Y183274D01*
X582638Y183272D01*
G02X579123Y182485I-1753J-413D01*
G01X578187Y186887D01*
G37*
G36*
G01X582312Y202511D02*
G02X585836Y203259I1762J374D01*
G01X586762Y198898D01*
X586763Y198896D01*
G02X583248Y198109I-1753J-413D01*
G01X582312Y202511D01*
G37*
G36*
G01X589961Y218883D02*
X590897Y214481D01*
G02X587373Y213733I-1762J-374D01*
G01X586447Y218094D01*
X586446Y218096D01*
G02X589961Y218883I1753J413D01*
G37*
G36*
G01X585372Y142248D02*
G02X588896Y142996I1762J374D01*
G01X589822Y138635D01*
X589823Y138633D01*
G02X586308Y137846I-1753J-413D01*
G01X585372Y142248D01*
G37*
G36*
G01X592704Y153607D02*
G02X596228Y154355I1762J374D01*
G01X597154Y149994D01*
X597155Y149992D01*
G02X593640Y149205I-1753J-413D01*
G01X592704Y153607D01*
G37*
G36*
G01X583383Y162435D02*
G02X586907Y163183I1762J374D01*
G01X587833Y158822D01*
X587834Y158820D01*
G02X584319Y158033I-1753J-413D01*
G01X583383Y162435D01*
G37*
G36*
G01X587008Y178059D02*
G02X590532Y178807I1762J374D01*
G01X591458Y174446D01*
X591459Y174444D01*
G02X587944Y173657I-1753J-413D01*
G01X587008Y178059D01*
G37*
G36*
G01X588826Y10237D02*
G02X584402I-2212J0D01*
G01Y15749D01*
G02X588826Y15748I2212J-1D01*
G01Y10237D01*
G37*
G36*
G01X581740Y14961D02*
G02X577316I-2212J0D01*
G01Y20474D01*
G02X581740Y20473I2212J-1D01*
G01Y14961D01*
G37*
G36*
G01Y43307D02*
G02X577316I-2212J0D01*
G01Y48820D01*
G02X581740Y48819I2212J-1D01*
G01Y43307D01*
G37*
G36*
G01X588826Y38583D02*
G02X584402I-2212J0D01*
G01Y44096D01*
G02X588826Y44095I2212J-1D01*
G01Y38583D01*
G37*
G36*
G01X574652Y10237D02*
G02X570230I-2211J0D01*
G01Y15749D01*
G02X574652Y15748I2211J-1D01*
G01Y10237D01*
G37*
G36*
G01X567566Y14961D02*
G02X563144I-2211J0D01*
G01Y20474D01*
G02X567566Y20473I2211J-1D01*
G01Y14961D01*
G37*
G36*
G01X560480Y10237D02*
G02X556056I-2212J0D01*
G01Y15749D01*
G02X560480Y15748I2212J-1D01*
G01Y10237D01*
G37*
G36*
G01X553392Y14961D02*
G02X548970I-2211J0D01*
G01Y20474D01*
G02X553392Y20473I2211J-1D01*
G01Y14961D01*
G37*
G36*
G01X546306Y10237D02*
G02X541884I-2211J0D01*
G01Y15749D01*
G02X546306Y15748I2211J-1D01*
G01Y10237D01*
G37*
G36*
G01X539220Y14961D02*
G02X534796I-2212J0D01*
G01Y20474D01*
G02X539220Y20473I2212J-1D01*
G01Y14961D01*
G37*
G36*
G01X532134Y10237D02*
G02X527710I-2212J0D01*
G01Y15749D01*
G02X532134Y15748I2212J-1D01*
G01Y10237D01*
G37*
G36*
G01X525046Y14961D02*
G02X520624I-2211J0D01*
G01Y20474D01*
G02X525046Y20473I2211J-1D01*
G01Y14961D01*
G37*
G36*
G01Y43307D02*
G02X520624I-2211J0D01*
G01Y48820D01*
G02X525046Y48819I2211J-1D01*
G01Y43307D01*
G37*
G36*
G01X532134Y38583D02*
G02X527710I-2212J0D01*
G01Y44096D01*
G02X532134Y44095I2212J-1D01*
G01Y38583D01*
G37*
G36*
G01X539220Y43307D02*
G02X534796I-2212J0D01*
G01Y48820D01*
G02X539220Y48819I2212J-1D01*
G01Y43307D01*
G37*
G36*
G01X546306Y38583D02*
G02X541884I-2211J0D01*
G01Y44096D01*
G02X546306Y44095I2211J-1D01*
G01Y38583D01*
G37*
G36*
G01X553392Y43307D02*
G02X548970I-2211J0D01*
G01Y48820D01*
G02X553392Y48819I2211J-1D01*
G01Y43307D01*
G37*
G36*
G01X560480Y38583D02*
G02X556056I-2212J0D01*
G01Y44096D01*
G02X560480Y44095I2212J-1D01*
G01Y38583D01*
G37*
G36*
G01X567566Y43307D02*
G02X563144I-2211J0D01*
G01Y48820D01*
G02X567566Y48819I2211J-1D01*
G01Y43307D01*
G37*
G36*
G01X574652Y38583D02*
G02X570230I-2211J0D01*
G01Y44096D01*
G02X574652Y44095I2211J-1D01*
G01Y38583D01*
G37*
G36*
G01X517960Y10237D02*
G02X513536I-2212J0D01*
G01Y15749D01*
G02X517960Y15748I2212J-1D01*
G01Y10237D01*
G37*
G36*
G01X510874Y14961D02*
G02X506450I-2212J0D01*
G01Y20474D01*
G02X510874Y20473I2212J-1D01*
G01Y14961D01*
G37*
G36*
G01X503786Y10237D02*
G02X499364I-2211J0D01*
G01Y15749D01*
G02X503786Y15748I2211J-1D01*
G01Y10237D01*
G37*
G36*
G01X496700Y14961D02*
G02X492278I-2211J0D01*
G01Y20474D01*
G02X496700Y20473I2211J-1D01*
G01Y14961D01*
G37*
G36*
G01X489614Y10237D02*
G02X485190I-2212J0D01*
G01Y15749D01*
G02X489614Y15748I2212J-1D01*
G01Y10237D01*
G37*
G36*
G01X482526Y14961D02*
G02X478104I-2211J0D01*
G01Y20474D01*
G02X482526Y20473I2211J-1D01*
G01Y14961D01*
G37*
G36*
G01X475440Y10237D02*
G02X471018I-2211J0D01*
G01Y15749D01*
G02X475440Y15748I2211J-1D01*
G01Y10237D01*
G37*
G36*
G01X468354Y14961D02*
G02X463930I-2212J0D01*
G01Y20474D01*
G02X468354Y20473I2212J-1D01*
G01Y14961D01*
G37*
G36*
G01X461266Y10237D02*
G02X456844I-2211J0D01*
G01Y15749D01*
G02X461266Y15748I2211J-1D01*
G01Y10237D01*
G37*
G36*
G01Y38583D02*
G02X456844I-2211J0D01*
G01Y44096D01*
G02X461266Y44095I2211J-1D01*
G01Y38583D01*
G37*
G36*
G01X468354Y43307D02*
G02X463930I-2212J0D01*
G01Y48820D01*
G02X468354Y48819I2212J-1D01*
G01Y43307D01*
G37*
G36*
G01X475440Y38583D02*
G02X471018I-2211J0D01*
G01Y44096D01*
G02X475440Y44095I2211J-1D01*
G01Y38583D01*
G37*
G36*
G01X482526Y43307D02*
G02X478104I-2211J0D01*
G01Y48820D01*
G02X482526Y48819I2211J-1D01*
G01Y43307D01*
G37*
G36*
G01X489614Y38583D02*
G02X485190I-2212J0D01*
G01Y44096D01*
G02X489614Y44095I2212J-1D01*
G01Y38583D01*
G37*
G36*
G01X496700Y43307D02*
G02X492278I-2211J0D01*
G01Y48820D01*
G02X496700Y48819I2211J-1D01*
G01Y43307D01*
G37*
G36*
G01X503786Y38583D02*
G02X499364I-2211J0D01*
G01Y44096D01*
G02X503786Y44095I2211J-1D01*
G01Y38583D01*
G37*
G36*
G01X510874Y43307D02*
G02X506450I-2212J0D01*
G01Y48820D01*
G02X510874Y48819I2212J-1D01*
G01Y43307D01*
G37*
G36*
G01X517960Y38583D02*
G02X513536I-2212J0D01*
G01Y44096D01*
G02X517960Y44095I2212J-1D01*
G01Y38583D01*
G37*
G36*
G01X454180Y14961D02*
G02X449758I-2211J0D01*
G01Y20474D01*
G02X454180Y20473I2211J-1D01*
G01Y14961D01*
G37*
G36*
G01X447094Y10237D02*
G02X442670I-2212J0D01*
G01Y15749D01*
G02X447094Y15748I2212J-1D01*
G01Y10237D01*
G37*
G36*
G01X440008Y14961D02*
G02X435584I-2212J0D01*
G01Y20474D01*
G02X440008Y20473I2212J-1D01*
G01Y14961D01*
G37*
G36*
G01X432920Y10237D02*
G02X428498I-2211J0D01*
G01Y15749D01*
G02X432920Y15748I2211J-1D01*
G01Y10237D01*
G37*
G36*
G01X425834Y14961D02*
G02X421410I-2212J0D01*
G01Y20474D01*
G02X425834Y20473I2212J-1D01*
G01Y14961D01*
G37*
G36*
G01X418748Y10237D02*
G02X414324I-2212J0D01*
G01Y15749D01*
G02X418748Y15748I2212J-1D01*
G01Y10237D01*
G37*
G36*
G01X411660Y14961D02*
G02X407238I-2211J0D01*
G01Y20474D01*
G02X411660Y20473I2211J-1D01*
G01Y14961D01*
G37*
G36*
G01X404574Y10237D02*
G02X400152I-2211J0D01*
G01Y15749D01*
G02X404574Y15748I2211J-1D01*
G01Y10237D01*
G37*
G36*
G01X397488Y14961D02*
G02X393064I-2212J0D01*
G01Y20474D01*
G02X397488Y20473I2212J-1D01*
G01Y14961D01*
G37*
G36*
G01Y43307D02*
G02X393064I-2212J0D01*
G01Y48820D01*
G02X397488Y48819I2212J-1D01*
G01Y43307D01*
G37*
G36*
G01X404574Y38583D02*
G02X400152I-2211J0D01*
G01Y44096D01*
G02X404574Y44095I2211J-1D01*
G01Y38583D01*
G37*
G36*
G01X411660Y43307D02*
G02X407238I-2211J0D01*
G01Y48820D01*
G02X411660Y48819I2211J-1D01*
G01Y43307D01*
G37*
G36*
G01X418748Y38583D02*
G02X414324I-2212J0D01*
G01Y44096D01*
G02X418748Y44095I2212J-1D01*
G01Y38583D01*
G37*
G36*
G01X425834Y43307D02*
G02X421410I-2212J0D01*
G01Y48820D01*
G02X425834Y48819I2212J-1D01*
G01Y43307D01*
G37*
G36*
G01X432920Y38583D02*
G02X428498I-2211J0D01*
G01Y44096D01*
G02X432920Y44095I2211J-1D01*
G01Y38583D01*
G37*
G36*
G01X440008Y43307D02*
G02X435584I-2212J0D01*
G01Y48820D01*
G02X440008Y48819I2212J-1D01*
G01Y43307D01*
G37*
G36*
G01X447094Y38583D02*
G02X442670I-2212J0D01*
G01Y44096D01*
G02X447094Y44095I2212J-1D01*
G01Y38583D01*
G37*
G36*
G01X454180Y43307D02*
G02X449758I-2211J0D01*
G01Y48820D01*
G02X454180Y48819I2211J-1D01*
G01Y43307D01*
G37*
G36*
G01X390400Y10237D02*
G02X385978I-2211J0D01*
G01Y15749D01*
G02X390400Y15748I2211J-1D01*
G01Y10237D01*
G37*
G36*
G01X383314Y14961D02*
G02X378892I-2211J0D01*
G01Y20474D01*
G02X383314Y20473I2211J-1D01*
G01Y14961D01*
G37*
G36*
G01X376228Y10237D02*
G02X371804I-2212J0D01*
G01Y15749D01*
G02X376228Y15748I2212J-1D01*
G01Y10237D01*
G37*
G36*
G01X369140Y14961D02*
G02X364718I-2211J0D01*
G01Y20474D01*
G02X369140Y20473I2211J-1D01*
G01Y14961D01*
G37*
G36*
G01X362054Y10237D02*
G02X357632I-2211J0D01*
G01Y15749D01*
G02X362054Y15748I2211J-1D01*
G01Y10237D01*
G37*
G36*
G01X354968Y14961D02*
G02X350544I-2212J0D01*
G01Y20474D01*
G02X354968Y20473I2212J-1D01*
G01Y14961D01*
G37*
G36*
G01X347882Y10237D02*
G02X343458I-2212J0D01*
G01Y15749D01*
G02X347882Y15748I2212J-1D01*
G01Y10237D01*
G37*
G36*
G01X340794Y14961D02*
G02X336372I-2211J0D01*
G01Y20474D01*
G02X340794Y20473I2211J-1D01*
G01Y14961D01*
G37*
G36*
G01Y43307D02*
G02X336372I-2211J0D01*
G01Y48820D01*
G02X340794Y48819I2211J-1D01*
G01Y43307D01*
G37*
G36*
G01X347882Y38583D02*
G02X343458I-2212J0D01*
G01Y44096D01*
G02X347882Y44095I2212J-1D01*
G01Y38583D01*
G37*
G36*
G01X354968Y43307D02*
G02X350544I-2212J0D01*
G01Y48820D01*
G02X354968Y48819I2212J-1D01*
G01Y43307D01*
G37*
G36*
G01X362054Y38583D02*
G02X357632I-2211J0D01*
G01Y44096D01*
G02X362054Y44095I2211J-1D01*
G01Y38583D01*
G37*
G36*
G01X369140Y43307D02*
G02X364718I-2211J0D01*
G01Y48820D01*
G02X369140Y48819I2211J-1D01*
G01Y43307D01*
G37*
G36*
G01X376228Y38583D02*
G02X371804I-2212J0D01*
G01Y44096D01*
G02X376228Y44095I2212J-1D01*
G01Y38583D01*
G37*
G36*
G01X383314Y43307D02*
G02X378892I-2211J0D01*
G01Y48820D01*
G02X383314Y48819I2211J-1D01*
G01Y43307D01*
G37*
G36*
G01X390400Y38583D02*
G02X385978I-2211J0D01*
G01Y44096D01*
G02X390400Y44095I2211J-1D01*
G01Y38583D01*
G37*
G36*
G01X19684Y548128D02*
G02Y486754I17717J-30687D01*
G01Y548128D01*
G37*
G36*
G01X574170Y131409D02*
G02X577694Y132157I1762J374D01*
G01X578620Y127796D01*
X578621Y127794D01*
G02X575106Y127007I-1753J-413D01*
G01X574170Y131409D01*
G37*
G36*
G01X545043Y310269D02*
X545157Y310282D01*
X549721D01*
X549722Y310281D01*
X549798Y310278D01*
G02X549899Y307273I-76J-1507D01*
G01X549785Y307260D01*
X545157D01*
X545043Y307273D01*
G02Y310269I178J1498D01*
G37*
G36*
G01X545100Y317236D02*
X545214Y317250D01*
X549842D01*
X549956Y317236D01*
G02Y314240I-178J-1498D01*
G01X549842Y314226D01*
X545278D01*
X545277Y314228D01*
X545201Y314231D01*
G02X545100Y317236I76J1507D01*
G37*
G36*
G01X546449Y325547D02*
X546563Y325560D01*
X551191D01*
X551305Y325547D01*
G02Y322551I-178J-1498D01*
G01X551191Y322538D01*
X546627D01*
X546626Y322539D01*
X546550Y322542D01*
G02X546449Y325547I76J1507D01*
G37*
G36*
G01X807088Y486754D02*
G02Y548128I-17718J30687D01*
G01Y486754D01*
G37*
G36*
G01X418244Y453186D02*
G02X414434Y451144I-1905J-1021D01*
G01X411481Y456655D01*
G02X415291Y458698I1905J1022D01*
G01X418244Y453186D01*
G37*
G36*
G01X409385D02*
G02X405575Y451144I-1905J-1021D01*
G01X402621Y456658D01*
X402601Y456698D01*
G02X406433Y458698I1927J979D01*
G01X409385Y453186D01*
G37*
G36*
G01X418244Y438226D02*
G02X414434Y436184I-1905J-1021D01*
G01X411481Y441695D01*
G02X415291Y443738I1905J1022D01*
G01X418244Y438226D01*
G37*
G36*
G01X409385D02*
G02X405575Y436184I-1905J-1021D01*
G01X402621Y441698D01*
X402601Y441738D01*
G02X406433Y443738I1927J979D01*
G01X409385Y438226D01*
G37*
G36*
G01X414195Y422057D02*
X414192Y422098D01*
X412076Y426048D01*
X412044Y426074D01*
G02X415530Y427943I1342J1682D01*
G01X415533Y427902D01*
X417650Y423951D01*
X417682Y423925D01*
G02X414195Y422057I-1343J-1681D01*
G37*
G36*
G01X406672Y427942D02*
X406676Y427901D01*
X408791Y423951D01*
X408823Y423926D01*
G02X405336Y422058I-1343J-1682D01*
G01X405332Y422099D01*
X403218Y426048D01*
X403186Y426074D01*
G02X406672Y427942I1342J1682D01*
G37*
G36*
G01X414195Y407097D02*
X414192Y407138D01*
X412075Y411088D01*
X412043Y411113D01*
G02X415530Y412982I1343J1682D01*
G01X415533Y412941D01*
X417650Y408991D01*
X417682Y408965D01*
G02X414195Y407097I-1343J-1681D01*
G37*
G36*
G01X406672Y412981D02*
X406676Y412940D01*
X408791Y408991D01*
X408823Y408966D01*
G02X405336Y407098I-1343J-1682D01*
G01X405332Y407139D01*
X403218Y411087D01*
X403186Y411113D01*
G02X406672Y412981I1342J1682D01*
G37*
G36*
G01X545015Y302778D02*
X545129Y302792D01*
X549757D01*
X549871Y302778D01*
G02Y299782I-178J-1498D01*
G01X549757Y299768D01*
X545193D01*
X545192Y299770D01*
X545116Y299773D01*
G02X545015Y302778I76J1507D01*
G37*
G36*
G01X547365Y238846D02*
G02Y242430I0J1792D01*
G01X551866D01*
G02X551865Y238846I-1J-1792D01*
G01X547365D01*
G37*
G36*
G01X546475Y246418D02*
G02Y250000I0J1791D01*
G01X550976D01*
G02X550975Y246418I-1J-1791D01*
G01X546475D01*
G37*
G36*
G01X546217Y254004D02*
G02Y257588I0J1792D01*
G01X550718D01*
G02X550717Y254004I-1J-1792D01*
G01X546217D01*
G37*
G36*
G01X522354Y180373D02*
G02X518750I-1802J0D01*
G01Y184874D01*
G02X522354Y184873I1802J-1D01*
G01Y180373D01*
G37*
G36*
G01X549000Y230108D02*
G02Y233692I0J1792D01*
G01X553501D01*
G02X553500Y230108I-1J-1792D01*
G01X549000D01*
G37*
G36*
G01X515748Y261254D02*
G02Y258432I0J-1411D01*
G01X511810D01*
G02X511811Y261254I1J1411D01*
G01X515748D01*
G37*
G36*
G01X500000Y296688D02*
G02Y293864I0J-1412D01*
G01X496062D01*
G02X496063Y296688I1J1412D01*
G01X500000D01*
G37*
G36*
G01X515748Y288814D02*
G02Y285990I0J-1412D01*
G01X511810D01*
G02X511811Y288814I1J1412D01*
G01X515748D01*
G37*
G36*
G01Y273066D02*
G02Y270242I0J-1412D01*
G01X511810D01*
G02X511811Y273066I1J1412D01*
G01X515748D01*
G37*
G36*
G01X500000Y249444D02*
G02Y246620I0J-1412D01*
G01X496062D01*
G02X496063Y249444I1J1412D01*
G01X500000D01*
G37*
G36*
G01Y288814D02*
G02Y285990I0J-1412D01*
G01X496062D01*
G02X496063Y288814I1J1412D01*
G01X500000D01*
G37*
G36*
G01Y284876D02*
G02Y282054I0J-1411D01*
G01X496062D01*
G02X496063Y284876I1J1411D01*
G01X500000D01*
G37*
G36*
G01Y280940D02*
G02Y278116I0J-1412D01*
G01X496062D01*
G02X496063Y280940I1J1412D01*
G01X500000D01*
G37*
G36*
G01Y277002D02*
G02Y274180I0J-1411D01*
G01X496062D01*
G02X496063Y277002I1J1411D01*
G01X500000D01*
G37*
G36*
G01Y273066D02*
G02Y270242I0J-1412D01*
G01X496062D01*
G02X496063Y273066I1J1412D01*
G01X500000D01*
G37*
G36*
G01Y269128D02*
G02Y266306I0J-1411D01*
G01X496062D01*
G02X496063Y269128I1J1411D01*
G01X500000D01*
G37*
G36*
G01Y261254D02*
G02Y258432I0J-1411D01*
G01X496062D01*
G02X496063Y261254I1J1411D01*
G01X500000D01*
G37*
G36*
G01Y241570D02*
G02Y238746I0J-1412D01*
G01X496062D01*
G02X496063Y241570I1J1412D01*
G01X500000D01*
G37*
G36*
G01Y245506D02*
G02Y242684I0J-1411D01*
G01X496062D01*
G02X496063Y245506I1J1411D01*
G01X500000D01*
G37*
G36*
G01Y253380D02*
G02Y250558I0J-1411D01*
G01X496062D01*
G02X496063Y253380I1J1411D01*
G01X500000D01*
G37*
G36*
G01Y257318D02*
G02Y254494I0J-1412D01*
G01X496062D01*
G02X496063Y257318I1J1412D01*
G01X500000D01*
G37*
G36*
G01X511811Y284876D02*
G02Y282054I0J-1411D01*
G01X507873D01*
G02X507874Y284876I1J1411D01*
G01X511811D01*
G37*
G36*
G01X515748Y280940D02*
G02Y278116I0J-1412D01*
G01X511810D01*
G02X511811Y280940I1J1412D01*
G01X515748D01*
G37*
G36*
G01X511811Y277002D02*
G02Y274180I0J-1411D01*
G01X507873D01*
G02X507874Y277002I1J1411D01*
G01X511811D01*
G37*
G36*
G01Y269128D02*
G02Y266306I0J-1411D01*
G01X507873D01*
G02X507874Y269128I1J1411D01*
G01X511811D01*
G37*
G36*
G01Y257318D02*
G02Y254494I0J-1412D01*
G01X507873D01*
G02X507874Y257318I1J1412D01*
G01X511811D01*
G37*
G36*
G01X515748Y253380D02*
G02Y250558I0J-1411D01*
G01X511810D01*
G02X511811Y253380I1J1411D01*
G01X515748D01*
G37*
G36*
G01X511811Y249444D02*
G02Y246620I0J-1412D01*
G01X507873D01*
G02X507874Y249444I1J1412D01*
G01X511811D01*
G37*
G36*
G01X515748Y245506D02*
G02Y242684I0J-1411D01*
G01X511810D01*
G02X511811Y245506I1J1411D01*
G01X515748D01*
G37*
G36*
G01X511811Y241570D02*
G02Y238746I0J-1412D01*
G01X507873D01*
G02X507874Y241570I1J1412D01*
G01X511811D01*
G37*
G36*
G01X500000Y292750D02*
G02Y289928I0J-1411D01*
G01X496062D01*
G02X496063Y292750I1J1411D01*
G01X500000D01*
G37*
G36*
G01Y300624D02*
G02Y297802I0J-1411D01*
G01X496062D01*
G02X496063Y300624I1J1411D01*
G01X500000D01*
G37*
G36*
G01X458104Y204725D02*
G02X455282I-1411J0D01*
G01Y208663D01*
G02X458104Y208662I1411J-1D01*
G01Y204725D01*
G37*
G36*
G01X462042Y200788D02*
G02X459218I-1412J0D01*
G01Y204726D01*
G02X462042Y204725I1412J-1D01*
G01Y200788D01*
G37*
G36*
G01X465978Y204725D02*
G02X463156I-1411J0D01*
G01Y208663D01*
G02X465978Y208662I1411J-1D01*
G01Y204725D01*
G37*
G36*
G01X469916Y200788D02*
G02X467092I-1412J0D01*
G01Y204726D01*
G02X469916Y204725I1412J-1D01*
G01Y200788D01*
G37*
G36*
G01X473852Y204725D02*
G02X471030I-1411J0D01*
G01Y208663D01*
G02X473852Y208662I1411J-1D01*
G01Y204725D01*
G37*
G36*
G01X477790Y200788D02*
G02X474966I-1412J0D01*
G01Y204726D01*
G02X477790Y204725I1412J-1D01*
G01Y200788D01*
G37*
G36*
G01X481726Y204725D02*
G02X478904I-1411J0D01*
G01Y208663D01*
G02X481726Y208662I1411J-1D01*
G01Y204725D01*
G37*
G36*
G01X485664Y200788D02*
G02X482840I-1412J0D01*
G01Y204726D01*
G02X485664Y204725I1412J-1D01*
G01Y200788D01*
G37*
G36*
G01X489600Y204725D02*
G02X486778I-1411J0D01*
G01Y208663D01*
G02X489600Y208662I1411J-1D01*
G01Y204725D01*
G37*
G36*
G01X512228Y180431D02*
G02X508626I-1801J0D01*
G01Y184932D01*
G02X512228Y184931I1801J-1D01*
G01Y180431D01*
G37*
G36*
G01X502104Y180489D02*
G02X498500I-1802J0D01*
G01Y184990D01*
G02X502104Y184989I1802J-1D01*
G01Y180489D01*
G37*
G36*
G01X492678Y180547D02*
G02X489076I-1801J0D01*
G01Y185048D01*
G02X492678Y185047I1801J-1D01*
G01Y180547D01*
G37*
G36*
G01X503937Y210074D02*
G02Y207250I0J-1412D01*
G01X499999D01*
G02X500000Y210074I1J1412D01*
G01X503937D01*
G37*
G36*
G01X500000Y214010D02*
G02Y211188I0J-1411D01*
G01X496062D01*
G02X496063Y214010I1J1411D01*
G01X500000D01*
G37*
G36*
G01Y217948D02*
G02Y215124I0J-1412D01*
G01X496062D01*
G02X496063Y217948I1J1412D01*
G01X500000D01*
G37*
G36*
G01Y221884D02*
G02Y219062I0J-1411D01*
G01X496062D01*
G02X496063Y221884I1J1411D01*
G01X500000D01*
G37*
G36*
G01Y225822D02*
G02Y222998I0J-1412D01*
G01X496062D01*
G02X496063Y225822I1J1412D01*
G01X500000D01*
G37*
G36*
G01Y229758D02*
G02Y226936I0J-1411D01*
G01X496062D01*
G02X496063Y229758I1J1411D01*
G01X500000D01*
G37*
G36*
G01Y233696D02*
G02Y230872I0J-1412D01*
G01X496062D01*
G02X496063Y233696I1J1412D01*
G01X500000D01*
G37*
G36*
G01Y237632D02*
G02Y234810I0J-1411D01*
G01X496062D01*
G02X496063Y237632I1J1411D01*
G01X500000D01*
G37*
G36*
G01X489600Y216536D02*
G02X486778I-1411J0D01*
G01Y220474D01*
G02X489600Y220473I1411J-1D01*
G01Y216536D01*
G37*
G36*
G01X485664D02*
G02X482840I-1412J0D01*
G01Y220474D01*
G02X485664Y220473I1412J-1D01*
G01Y216536D01*
G37*
G36*
G01X481726D02*
G02X478904I-1411J0D01*
G01Y220474D01*
G02X481726Y220473I1411J-1D01*
G01Y216536D01*
G37*
G36*
G01X477790D02*
G02X474966I-1412J0D01*
G01Y220474D01*
G02X477790Y220473I1412J-1D01*
G01Y216536D01*
G37*
G36*
G01X473852D02*
G02X471030I-1411J0D01*
G01Y220474D01*
G02X473852Y220473I1411J-1D01*
G01Y216536D01*
G37*
G36*
G01X469916D02*
G02X467092I-1412J0D01*
G01Y220474D01*
G02X469916Y220473I1412J-1D01*
G01Y216536D01*
G37*
G36*
G01X465978D02*
G02X463156I-1411J0D01*
G01Y220474D01*
G02X465978Y220473I1411J-1D01*
G01Y216536D01*
G37*
G36*
G01X462042D02*
G02X459218I-1412J0D01*
G01Y220474D01*
G02X462042Y220473I1412J-1D01*
G01Y216536D01*
G37*
G36*
G01X458104D02*
G02X455282I-1411J0D01*
G01Y220474D01*
G02X458104Y220473I1411J-1D01*
G01Y216536D01*
G37*
G36*
G01X391176Y212599D02*
G02X388352I-1412J0D01*
G01Y216537D01*
G02X391176Y216536I1412J-1D01*
G01Y212599D01*
G37*
G36*
G01X402986Y200788D02*
G02X400164I-1411J0D01*
G01Y204726D01*
G02X402986Y204725I1411J-1D01*
G01Y200788D01*
G37*
G36*
G01X410860D02*
G02X408038I-1411J0D01*
G01Y204726D01*
G02X410860Y204725I1411J-1D01*
G01Y200788D01*
G37*
G36*
G01X418734D02*
G02X415912I-1411J0D01*
G01Y204726D01*
G02X418734Y204725I1411J-1D01*
G01Y200788D01*
G37*
G36*
G01X426608D02*
G02X423786I-1411J0D01*
G01Y204726D01*
G02X426608Y204725I1411J-1D01*
G01Y200788D01*
G37*
G36*
G01X434482D02*
G02X431660I-1411J0D01*
G01Y204726D01*
G02X434482Y204725I1411J-1D01*
G01Y200788D01*
G37*
G36*
G01X438420Y204725D02*
G02X435596I-1412J0D01*
G01Y208663D01*
G02X438420Y208662I1412J-1D01*
G01Y204725D01*
G37*
G36*
G01X442356Y200788D02*
G02X439534I-1411J0D01*
G01Y204726D01*
G02X442356Y204725I1411J-1D01*
G01Y200788D01*
G37*
G36*
G01X446294Y204725D02*
G02X443470I-1412J0D01*
G01Y208663D01*
G02X446294Y208662I1412J-1D01*
G01Y204725D01*
G37*
G36*
G01X450230Y200788D02*
G02X447408I-1411J0D01*
G01Y204726D01*
G02X450230Y204725I1411J-1D01*
G01Y200788D01*
G37*
G36*
G01Y216536D02*
G02X447408I-1411J0D01*
G01Y220474D01*
G02X450230Y220473I1411J-1D01*
G01Y216536D01*
G37*
G36*
G01X446294D02*
G02X443470I-1412J0D01*
G01Y220474D01*
G02X446294Y220473I1412J-1D01*
G01Y216536D01*
G37*
G36*
G01X442356D02*
G02X439534I-1411J0D01*
G01Y220474D01*
G02X442356Y220473I1411J-1D01*
G01Y216536D01*
G37*
G36*
G01X438420D02*
G02X435596I-1412J0D01*
G01Y220474D01*
G02X438420Y220473I1412J-1D01*
G01Y216536D01*
G37*
G36*
G01X434482D02*
G02X431660I-1411J0D01*
G01Y220474D01*
G02X434482Y220473I1411J-1D01*
G01Y216536D01*
G37*
G36*
G01X430546D02*
G02X427722I-1412J0D01*
G01Y220474D01*
G02X430546Y220473I1412J-1D01*
G01Y216536D01*
G37*
G36*
G01X426608D02*
G02X423786I-1411J0D01*
G01Y220474D01*
G02X426608Y220473I1411J-1D01*
G01Y216536D01*
G37*
G36*
G01X422672D02*
G02X419848I-1412J0D01*
G01Y220474D01*
G02X422672Y220473I1412J-1D01*
G01Y216536D01*
G37*
G36*
G01X418734D02*
G02X415912I-1411J0D01*
G01Y220474D01*
G02X418734Y220473I1411J-1D01*
G01Y216536D01*
G37*
G36*
G01X430546Y204725D02*
G02X427722I-1412J0D01*
G01Y208663D01*
G02X430546Y208662I1412J-1D01*
G01Y204725D01*
G37*
G36*
G01X422672D02*
G02X419848I-1412J0D01*
G01Y208663D01*
G02X422672Y208662I1412J-1D01*
G01Y204725D01*
G37*
G36*
G01X414798D02*
G02X411974I-1412J0D01*
G01Y208663D01*
G02X414798Y208662I1412J-1D01*
G01Y204725D01*
G37*
G36*
G01X406924D02*
G02X404100I-1412J0D01*
G01Y208663D01*
G02X406924Y208662I1412J-1D01*
G01Y204725D01*
G37*
G36*
G01X399050D02*
G02X396226I-1412J0D01*
G01Y208663D01*
G02X399050Y208662I1412J-1D01*
G01Y204725D01*
G37*
G36*
G01X395112Y200788D02*
G02X392290I-1411J0D01*
G01Y204726D01*
G02X395112Y204725I1411J-1D01*
G01Y200788D01*
G37*
G36*
G01X690203Y118988D02*
G02X687564Y119686I-1227J697D01*
G01X687565D01*
Y122834D01*
G02X690204Y123533I1412J1D01*
G03X690899I347J198D01*
G02X693538Y122835I1227J-698D01*
G01Y119686D01*
G02X690899Y118988I-1412J0D01*
G03X690203I-348J-197D01*
G37*
G36*
G01X680754D02*
G02X678115Y119686I-1227J697D01*
G01X678116D01*
Y122834D01*
G02X680755Y123532I1412J1D01*
G03X681451I348J198D01*
G02X684090Y122834I1227J-697D01*
G01X684089D01*
Y119685D01*
X684088D01*
G02X681450Y118988I-1411J0D01*
G03X680754I-348J-198D01*
G37*
G36*
G01X671305D02*
G02X668666Y119686I-1227J697D01*
G01X668667D01*
Y122834D01*
G02X671306Y123532I1412J1D01*
G03X672002I348J198D01*
G02X674641Y122834I1227J-697D01*
G01X674640D01*
Y119685D01*
X674639D01*
G02X672001Y118988I-1411J0D01*
G03X671305I-348J-198D01*
G37*
G36*
G01X661856D02*
G02X659217Y119686I-1227J697D01*
G01X659218D01*
Y122833D01*
G02X661857Y123532I1412J1D01*
G03X662552I347J198D01*
G02X665190Y122834I1227J-698D01*
G01Y119685D01*
G02X662552Y118988I-1411J0D01*
G03X661856I-348J-198D01*
G37*
G36*
G01X655786Y118047D02*
X657478D01*
G02X657479Y115025I1J-1511D01*
G01X654331Y115024D01*
G02X653474Y117780I0J1511D01*
G03Y118440I-227J330D01*
G02X652818Y119685I855J1246D01*
G01Y122834D01*
G02X653474Y124080I1511J0D01*
G03Y124739I-227J330D01*
G02Y127229I857J1245D01*
G03Y127888I-227J330D01*
G02X652818Y129134I855J1246D01*
G01Y132283D01*
G02X653179Y133262I1512J-1D01*
G03X652874Y133922I-305J260D01*
G01X651180D01*
G02X651181Y136944I1J1511D01*
G01X652873D01*
G03X653178Y137603I0J400D01*
G02X652818Y138582I1151J979D01*
G01Y141732D01*
G02X653179Y142711I1512J-1D01*
G03X652874Y143370I-305J259D01*
G01X651180D01*
G02X651181Y146394I1J1512D01*
G01X652873D01*
G03X653178Y147052I0J400D01*
G02X652818Y148031I1151J979D01*
G01Y151181D01*
G02X655842I1512J0D01*
G01Y148030D01*
G02X655187Y146786I-1512J1D01*
G03Y146127I227J-329D01*
G02X655186Y143637I-857J-1245D01*
G03Y142977I227J-330D01*
G02X655842Y141732I-855J-1246D01*
G01Y138581D01*
G02X655187Y137337I-1512J1D01*
G03Y136678I227J-329D01*
G02X655186Y134188I-857J-1245D01*
G03Y133528I227J-330D01*
G02X655842Y132283I-855J-1246D01*
G01Y129133D01*
G02X655481Y128155I-1512J2D01*
G03X655786Y127496I305J-259D01*
G01X657481D01*
G02X657480Y124472I-1J-1512D01*
G01X655786D01*
G03X655481Y123813I0J-400D01*
G02X655842Y122834I-1151J-980D01*
G01Y119684D01*
G02X655482Y118706I-1512J1D01*
G03X655786Y118047I305J-259D01*
G37*
G54D43*
X98425Y472441D03*
X137795D03*
G54D40*
X27058Y25484D03*
X81539Y542850D03*
X798456Y26432D03*
G54D47*
X389764Y460630D03*
X437008D03*
G54D42*
X116063Y14567D03*
G54D46*
X295276Y531496D03*
G54D45*
X781496Y198819D03*
G54D48*
X531496Y531496D03*
G54D44*
X596457Y116142D03*
X374016Y156221D03*
G54D41*
X116066Y39074D03*
G54D14*
X54697Y165269D03*
X58697D03*
X59600Y152000D03*
X71200Y137200D03*
X39416Y206616D03*
X65500Y237800D03*
X70500D03*
X75500D03*
X23800Y211200D03*
X27500D03*
X59700Y178600D03*
X68400Y177950D03*
X76800Y178200D03*
X46194Y179835D03*
X50194D03*
X39320Y213823D03*
X64000Y178400D03*
X72800Y178200D03*
X22150Y203550D03*
X26150Y230850D03*
X23100Y283200D03*
X22750Y275450D03*
X23500Y296700D03*
X68300Y292200D03*
X45650Y250280D03*
X49320D03*
X40290Y239814D03*
X35405Y239808D03*
X32469Y250280D03*
X37469D03*
X69143Y334598D03*
X47443Y334198D03*
X27947Y334066D03*
X28000Y326500D03*
X24000Y301750D03*
X23400Y309500D03*
X67800Y318000D03*
X67700Y321500D03*
X58900Y334180D03*
X62325Y334068D03*
X37900Y334380D03*
X41325Y334268D03*
X65500Y378800D03*
X43000Y378233D03*
X22000Y378352D03*
X53500Y403150D03*
X49700Y402000D03*
X50700Y378233D03*
X54800Y373600D03*
X29900Y378252D03*
X38200Y373800D03*
X34100D03*
X73100Y378700D03*
X60400Y373600D03*
X77200Y374000D03*
X65375Y392835D03*
X35800Y363400D03*
X40100D03*
X92300Y199400D03*
Y209400D03*
Y204400D03*
X90800Y217900D03*
X82600Y232000D03*
X78850Y221000D03*
X87300Y230650D03*
X92300Y190900D03*
X81300Y178050D03*
X85700Y178000D03*
X92300Y194900D03*
X78800Y205900D03*
X92300Y213900D03*
X89800Y178000D03*
X80688Y281695D03*
Y276695D03*
X93884Y242333D03*
X90238Y334391D03*
X78600Y321700D03*
X78700Y317400D03*
X102300Y329100D03*
X80700Y309400D03*
X80600Y304600D03*
Y334580D03*
X84025Y334468D03*
X102400Y333900D03*
X106500D03*
X89895Y378426D03*
X85795D03*
X102395Y373793D03*
X93695Y378426D03*
X81300Y374000D03*
X98295Y373793D03*
X106709Y383400D03*
X112023Y383013D03*
X78171Y363195D03*
X82171D03*
X99266Y362988D03*
X103266D03*
X104900Y412200D03*
X102679Y391150D03*
X112638Y391197D03*
X107582Y391266D03*
X102850Y452650D03*
X182100Y105500D03*
X155991Y110061D03*
X200550Y111350D03*
X152800Y113400D03*
X164020Y101127D03*
X158612Y126645D03*
X198202Y135298D03*
X201139Y121630D03*
X172800Y141001D03*
X180300Y175400D03*
X145585Y132451D03*
X197100Y298800D03*
X162522Y331774D03*
X196600Y306800D03*
X250137Y36053D03*
X242610Y53714D03*
X234450Y73000D03*
X261102Y77900D03*
X248169Y74454D03*
X242727Y63391D03*
X241750Y98250D03*
X238867Y63650D03*
X255300Y72600D03*
X234693Y57400D03*
X255154Y69177D03*
X233759Y64752D03*
X220228Y63651D03*
X245800Y279200D03*
X207600Y292400D03*
X204400Y288700D03*
X248900Y282932D03*
X259629Y281000D03*
X242351Y282900D03*
X228300Y280900D03*
X219400Y279400D03*
X262800Y277835D03*
X242400Y289700D03*
X242402Y286300D03*
X225500Y278900D03*
X222320Y277658D03*
X207500Y278400D03*
X204997Y280702D03*
X253575Y320167D03*
X235500Y320100D03*
X218500Y320200D03*
X222000Y310600D03*
X212198Y328316D03*
X208648Y328452D03*
X261365Y324351D03*
X245943Y326300D03*
X246100Y329700D03*
X230400Y326200D03*
Y329600D03*
X253245Y329698D03*
X253154Y326227D03*
X241556Y340111D03*
X237483Y339988D03*
X230000Y336500D03*
X233400Y336600D03*
X218400Y326600D03*
X218300Y330000D03*
X230400Y348000D03*
X255500Y423361D03*
X237600Y390500D03*
X261581Y370979D03*
X256172Y409530D03*
X261996Y365663D03*
X263250Y423411D03*
X257996Y365663D03*
X259800Y423400D03*
X256900Y380900D03*
X281700Y52285D03*
X285500D03*
X308591Y68928D03*
X304591D03*
X308591Y73074D03*
X311182Y58692D03*
X276700Y66700D03*
X283385Y100227D03*
X287385D03*
X319533Y114283D03*
X291385Y100227D03*
X295385D03*
X306196Y110209D03*
X310711Y113820D03*
X314772Y108292D03*
X300311Y60800D03*
X300385Y108227D03*
X311182Y62800D03*
X272937Y90362D03*
X266895Y100227D03*
X306280Y82574D03*
X283393Y92325D03*
X301280Y82574D03*
X272937Y85862D03*
X304591Y73074D03*
X318773Y108083D03*
X278039Y82185D03*
X279385Y100227D03*
X292030Y90574D03*
X292385Y108227D03*
X280298Y95556D03*
X296280Y82574D03*
X324026Y115936D03*
X321343Y122343D03*
X321051Y134028D03*
X304529Y118792D03*
X317700Y275400D03*
X270143Y276969D03*
X323681Y259023D03*
X319881D03*
X284498Y299976D03*
X299635Y292650D03*
X317600Y278800D03*
X319543Y290159D03*
X303032Y289900D03*
X268400Y281000D03*
X266406Y277835D03*
X306292Y252825D03*
X302262Y262642D03*
X299635Y288650D03*
X292225Y288267D03*
X297021Y346579D03*
X287350Y351200D03*
X319550Y347169D03*
X305147Y354706D03*
X316050Y342200D03*
X287350Y357700D03*
X322500Y353700D03*
X301500Y337500D03*
X320650Y336456D03*
X306060Y337640D03*
X310200Y337600D03*
X294250Y325000D03*
X277150Y332000D03*
X273165Y320351D03*
X325500Y325400D03*
X314241Y308459D03*
X314300Y311900D03*
X308180Y305200D03*
X305628Y320511D03*
X301628D03*
X325500Y321400D03*
X314400Y327851D03*
X314045Y302900D03*
X314500Y324251D03*
X319100Y330600D03*
X305628Y324511D03*
X324100Y307814D03*
X265365Y324351D03*
X281150Y332000D03*
X288536Y314764D03*
X275696Y314340D03*
X308398Y386479D03*
X304205Y382450D03*
X304398Y386479D03*
X292800Y363800D03*
X300019Y379524D03*
X296079D03*
X325200Y365100D03*
X312398Y386479D03*
X266300Y412100D03*
X270618Y385867D03*
X268004Y424361D03*
X323448Y405064D03*
X266500Y364000D03*
X325651Y439668D03*
X328600Y114400D03*
X328711Y108053D03*
X335722Y94574D03*
X329722D03*
X374616Y172378D03*
X370061Y172433D03*
X355500Y144500D03*
X342000Y141600D03*
X331649Y126111D03*
X339049Y124238D03*
X335994Y126119D03*
X341913Y145049D03*
X374915Y176442D03*
X359969Y124510D03*
X349911Y136954D03*
X341757Y211056D03*
X337157Y206052D03*
X335701Y223995D03*
X352047Y220590D03*
X357546Y230354D03*
X360710Y231897D03*
X376306Y182715D03*
X351723Y178499D03*
X354143Y183439D03*
X362260Y184360D03*
X364169Y188366D03*
X366460Y191794D03*
X368558Y194540D03*
X379415Y194608D03*
X370570Y198219D03*
X371124Y178760D03*
X372517Y182362D03*
X380400Y287400D03*
X382000Y296500D03*
X384600Y285600D03*
X368714Y261134D03*
X339500Y260400D03*
X327868Y290125D03*
X365996Y287265D03*
Y272841D03*
X366169Y246591D03*
X370669D03*
X338650Y281350D03*
X361996Y272841D03*
X379000Y272600D03*
X384300Y291100D03*
X346900Y281300D03*
X343100D03*
X357996Y272841D03*
X328134Y252720D03*
X332000Y266336D03*
X376633Y261543D03*
X340280Y253765D03*
X337500Y266050D03*
X358096Y262268D03*
X341998Y256700D03*
X368610Y257299D03*
X376633Y256851D03*
X385887Y305222D03*
X381396Y302610D03*
X335400Y337400D03*
X345700Y349773D03*
X337600Y349600D03*
X339000Y344700D03*
X330000Y345800D03*
X335882Y309823D03*
X327400Y342600D03*
X386159Y337080D03*
X368050Y337200D03*
X370250Y347600D03*
X379148Y337184D03*
X384341Y315377D03*
X377324Y302844D03*
X360050Y337200D03*
X348600Y323900D03*
X359400Y347200D03*
X346500Y302500D03*
X356550Y337200D03*
X348596Y337250D03*
X347750Y315850D03*
X352396Y337200D03*
X331026Y303354D03*
X328100Y331300D03*
X329364Y316949D03*
X364050Y337200D03*
X374250Y347600D03*
X359200Y315800D03*
X355200D03*
X360300Y323900D03*
X363400Y315800D03*
X344000Y388500D03*
X340375Y365944D03*
X331765Y386535D03*
X367450Y409955D03*
X367350Y406455D03*
X360000Y410000D03*
X337592Y405027D03*
X327365Y433732D03*
X337900Y431200D03*
X448300Y337500D03*
X444100Y341000D03*
X444200Y337600D03*
X444100Y345000D03*
X440300Y337500D03*
X444959Y352053D03*
X389559Y337103D03*
X421500Y337500D03*
X427500D03*
X448431Y348737D03*
X401700Y337350D03*
X392959Y337099D03*
X405921Y347159D03*
X430464Y347078D03*
X390550Y326820D03*
X405783Y339318D03*
X448500Y424000D03*
X445000Y422000D03*
X452300Y337500D03*
X468300D03*
X456550D03*
X464300D03*
X460800Y337562D03*
X460300Y333500D03*
X481359Y347727D03*
X467774Y362151D03*
X467100Y357500D03*
X464500Y347410D03*
X502138Y348500D03*
X472463Y329837D03*
X468500Y347500D03*
X476200Y334900D03*
X506262Y348500D03*
X510138D03*
X479640Y334674D03*
X485100Y366800D03*
X490000Y363700D03*
X502850Y368500D03*
X503800Y382700D03*
X510200Y363209D03*
X506200D03*
X494400Y363800D03*
X499100Y363409D03*
X452500Y423500D03*
X510700Y367309D03*
X506700D03*
X489600Y367209D03*
X474200Y367500D03*
X457599Y419642D03*
X496300Y378935D03*
X489500Y371200D03*
X542627Y324049D03*
X546627D03*
X551127D03*
X555127D03*
X541278Y315738D03*
X545278D03*
X549778D03*
X553778D03*
X541221Y308771D03*
X545221D03*
X549721D03*
X553721D03*
X541193Y301280D03*
X545193D03*
X549693D03*
X553693D03*
X552200Y339300D03*
X556800D03*
X519263Y327092D03*
X538476Y334365D03*
X538436Y330918D03*
X534100Y342410D03*
X536200Y348300D03*
X540200D03*
X550100D03*
X546100D03*
X554685Y333410D03*
X547927Y342199D03*
X543646Y342347D03*
X539446D03*
X519629Y330448D03*
X521914Y332907D03*
X557411Y481025D03*
X554250Y457500D03*
X574250Y466900D03*
X545880Y485940D03*
X539040Y480090D03*
X562460Y457580D03*
X517125Y488975D03*
X632416Y31609D03*
X627603Y43523D03*
X627500Y19339D03*
X626786Y31227D03*
X634400Y102000D03*
X630600D03*
X627500Y64500D03*
X629500Y61500D03*
X634169Y166500D03*
X618250Y162081D03*
X618400Y173443D03*
X617600Y134400D03*
X635852Y133715D03*
X627455Y185364D03*
X634000Y234200D03*
X630000D03*
X636363Y209944D03*
X632363D03*
X628363D03*
X624363D03*
X622400Y216750D03*
X633800Y239600D03*
X629900Y239700D03*
X633800Y245700D03*
X629900Y245800D03*
X634100Y252000D03*
X629900D03*
X618300Y288745D03*
X632750Y292195D03*
Y295641D03*
X594025Y280017D03*
X590050Y337950D03*
X590200Y334350D03*
X612300Y356850D03*
X634000Y306300D03*
X631800Y316137D03*
X603650Y315500D03*
X629250Y310491D03*
Y306491D03*
X626405Y314991D03*
X629250Y344900D03*
Y348900D03*
X623063Y357337D03*
X602649Y349033D03*
X594400Y357000D03*
Y353000D03*
X597450Y324750D03*
Y320750D03*
X627020Y393364D03*
X598152Y370130D03*
X629770Y369320D03*
X594200Y390400D03*
X629400Y414324D03*
X584280Y424030D03*
X624200Y372500D03*
X620260Y389940D03*
X589394Y384572D03*
X589391Y378202D03*
X627140Y381353D03*
X631140D03*
X594200Y395200D03*
X604832Y395220D03*
X630000Y464900D03*
X626300D03*
X577330Y464430D03*
X599900Y438300D03*
X587890Y426720D03*
X577300Y460300D03*
X588400Y469450D03*
X634050Y469200D03*
X588663Y460037D03*
X581250Y480550D03*
X585420Y456480D03*
X633676Y460080D03*
X617000Y468700D03*
X620600Y458500D03*
X647216Y31601D03*
X667900Y40800D03*
X643816Y31573D03*
X640144Y40969D03*
X643103Y13803D03*
X664301Y40104D03*
Y49998D03*
X638103Y13100D03*
X640416Y31609D03*
X647103Y13964D03*
X694365Y94458D03*
Y90958D03*
X686279Y94494D03*
Y90994D03*
X678225Y94496D03*
Y90996D03*
X670146Y94505D03*
Y91005D03*
X662047Y94539D03*
Y91039D03*
X654037Y94708D03*
Y91208D03*
X654330Y113385D03*
X688976D03*
X644100Y111811D03*
X668100Y56100D03*
X651564Y52638D03*
X644500Y65759D03*
X640600Y111600D03*
X641003Y68809D03*
X654330Y154330D03*
X657480Y151219D03*
X663778Y166928D03*
X673227Y157479D03*
X673229Y166929D03*
Y173228D03*
X670080Y148030D03*
X679526Y144880D03*
X660629Y138584D03*
Y141732D03*
X688978Y135435D03*
X682679D03*
X676379D03*
X695274Y135431D03*
X698425Y129134D03*
X663778Y160629D03*
Y154330D03*
Y135431D03*
X692124D03*
X673227Y144880D03*
X685825Y138581D03*
X679526D03*
X673227D03*
X666928D03*
X648032Y129134D03*
X657480Y122834D03*
X698425Y135433D03*
Y138582D03*
X692125D03*
X682677Y148031D03*
X688976D03*
X695275D03*
X682677Y154330D03*
X688976D03*
X695275D03*
Y160629D03*
X688976D03*
X682677Y160630D03*
X679527Y163779D03*
X695275Y166929D03*
X688976D03*
X682677D03*
X695275Y173228D03*
X688976D03*
X682677D03*
X654330Y170078D03*
X648031Y163779D03*
X654330D03*
X651181Y157480D03*
X670078Y154330D03*
X644882Y157480D03*
X666929Y125984D03*
X657480Y129134D03*
X651181Y151181D03*
X698425Y116535D03*
X648059Y151191D03*
X685827Y125985D03*
X676377Y116536D03*
X663778Y176377D03*
Y173227D03*
Y170078D03*
X670078Y166928D03*
Y173227D03*
X654330Y176377D03*
X639108Y167800D03*
X648057Y141721D03*
X648032Y135434D03*
Y122835D03*
X660629Y116536D03*
X666929Y116535D03*
X698426Y122835D03*
X692148Y129119D03*
X670116Y132283D03*
X673229Y125985D03*
X679528D03*
X660629Y170078D03*
Y173227D03*
X654330Y157480D03*
X651181Y154330D03*
X670078Y170078D03*
X654330Y173228D03*
X651181Y166929D03*
X660630Y160630D03*
X640775Y156218D03*
X648031Y157480D03*
X663779Y151181D03*
X666929Y148031D03*
X663779Y132283D03*
X663778Y144883D03*
Y138584D03*
X651181Y141732D03*
Y132283D03*
Y122834D03*
X644882Y154331D03*
X637952Y142515D03*
X640500Y125000D03*
X660629Y144883D03*
X657481Y132284D03*
X670078Y151181D03*
X637343Y171335D03*
Y174835D03*
X657480Y154330D03*
X644882Y173228D03*
Y176378D03*
Y170078D03*
X648031D03*
X670078Y157480D03*
X673228Y148031D03*
X692126Y125984D03*
X685827Y116535D03*
X670079Y125985D03*
X682678D03*
X676378D03*
X688977D03*
X676378Y119686D03*
X666929Y119685D03*
X663780Y125985D03*
X657479Y116536D03*
X654330Y116535D03*
Y119685D03*
Y122834D03*
X657480Y125984D03*
X654331D03*
X654330Y129134D03*
Y132283D03*
Y135433D03*
X651181D03*
X654330Y138582D03*
Y141732D03*
Y144882D03*
X651181D03*
X654330Y148031D03*
Y151181D03*
X679452Y209815D03*
X651181Y188976D03*
X679527Y182679D03*
Y188975D03*
X676379Y182678D03*
X692126Y182676D03*
Y185827D03*
Y179527D03*
X676379Y192126D03*
X670080Y182678D03*
X697069Y207157D03*
X663400Y234100D03*
X663200Y238100D03*
X682676Y179526D03*
Y188975D03*
X682677Y182677D03*
X682676Y185826D03*
X676377Y201574D03*
Y204723D03*
X685826Y198424D03*
X663778Y182676D03*
Y179526D03*
X654330Y182676D03*
X660629Y192125D03*
X666929D03*
X660630Y198425D03*
X676377Y198424D03*
X685826Y201574D03*
X682677Y192125D03*
X688976D03*
X698425D03*
X640931Y181102D03*
X646594Y210875D03*
X640584Y194127D03*
X683913Y213313D03*
X695275Y198425D03*
X692125Y198423D03*
X651181Y192125D03*
X663779D03*
X657480D03*
X670078D03*
X654330Y185826D03*
Y179526D03*
X685826Y192125D03*
X692125D03*
X667353Y233486D03*
X640363Y209944D03*
X638479Y230640D03*
X674023Y213815D03*
X640509Y177600D03*
X674172Y210095D03*
X679400Y213300D03*
X679527Y198424D03*
X697149Y219742D03*
X692949D03*
X695600Y240354D03*
X682700D03*
X695625Y282250D03*
X669125Y280405D03*
X663000Y249200D03*
X663100Y252700D03*
X674841Y262854D03*
X695383Y266855D03*
X644153Y278745D03*
X660400Y271900D03*
X678500Y240324D03*
X691100Y240354D03*
X686900D03*
X668600Y242800D03*
X669450Y284900D03*
X695600Y244354D03*
X695375Y260875D03*
X637500Y362400D03*
X680300Y384900D03*
X693500Y373300D03*
X694765Y406915D03*
X685750Y419460D03*
X642900Y395400D03*
X674150Y415380D03*
X654770Y401166D03*
X645970Y399130D03*
X669031Y388383D03*
X665031D03*
X653360Y386210D03*
X680700Y378200D03*
X687150Y385550D03*
X675031Y389383D03*
X653007Y382828D03*
X658601Y401800D03*
X673900Y418880D03*
X637500Y365900D03*
X672800Y438832D03*
X696950Y441400D03*
X667414Y431956D03*
X692200Y428700D03*
X671640Y454410D03*
X683250Y437813D03*
X710378Y96399D03*
Y92899D03*
X702391Y94510D03*
Y91010D03*
X722673Y105444D03*
X736785Y110185D03*
X737800Y106525D03*
X717197Y109646D03*
X726100Y107200D03*
X734709Y106595D03*
X731000Y106315D03*
X734212Y109995D03*
X725943Y100147D03*
X744833Y78995D03*
X754572Y86923D03*
X754528Y83228D03*
X745100Y97500D03*
X719010Y107281D03*
X707649Y110002D03*
X710517Y106823D03*
X750773Y74636D03*
X747919Y76667D03*
X720744Y92427D03*
X704849Y107385D03*
X733069Y166930D03*
X704725Y135434D03*
X707874Y141732D03*
X701574Y138582D03*
X701575Y135433D03*
X704724Y132283D03*
X726770Y166930D03*
Y173229D03*
X701574Y148031D03*
X707873D03*
X701574Y154330D03*
X707873D03*
Y160629D03*
X701574D03*
X707873Y166929D03*
X701574D03*
X707873Y173228D03*
X701574D03*
X711023Y141732D03*
X714172Y173227D03*
Y144880D03*
Y151180D03*
X717322Y144880D03*
Y151180D03*
X714172Y163778D03*
Y157479D03*
X717322Y163778D03*
Y157479D03*
Y166928D03*
X720472Y173228D03*
Y148031D03*
Y141732D03*
Y160629D03*
Y154330D03*
X720471Y166928D03*
X717322Y141731D03*
X704725Y122835D03*
X729921Y157480D03*
X739952Y120649D03*
X740952Y126815D03*
X707874Y116535D03*
X743100Y114700D03*
X737352Y145885D03*
X726771Y122835D03*
X729921Y122834D03*
X737702Y128565D03*
X729921Y132283D03*
Y129134D03*
X711023Y116535D03*
X726771Y163779D03*
X741754Y134617D03*
X729921Y135433D03*
X739622Y137008D03*
X729921Y138582D03*
Y144882D03*
X714173Y116535D03*
X717322D03*
X707873Y129133D03*
X720473Y116536D03*
X704725D03*
X714173Y122834D03*
X720472D03*
X741077Y159790D03*
X757471Y148193D03*
X723621Y148031D03*
Y154330D03*
Y160629D03*
Y166929D03*
Y173228D03*
X707874Y122835D03*
X723621Y135433D03*
Y129133D03*
Y141732D03*
X701575Y122835D03*
X714173Y141732D03*
X723622Y116535D03*
X704723Y129133D03*
X701574D03*
X711022D03*
X714172D03*
X729921Y125984D03*
X711023Y173228D03*
X741952Y173115D03*
X738352Y174615D03*
X729920Y176378D03*
Y173229D03*
X736219Y170079D03*
X733070D03*
X746750Y157700D03*
X729921Y148031D03*
Y141732D03*
Y163779D03*
X750550Y135200D03*
X729921Y160629D03*
X701575Y116536D03*
X729921Y154330D03*
X717322Y182676D03*
X711024Y188976D03*
X701575Y182676D03*
X711022Y185825D03*
X701575Y185827D03*
Y179527D03*
X726770Y179528D03*
Y185827D03*
Y192126D03*
X730694Y224473D03*
X726656Y235244D03*
X711022Y179526D03*
X714172D03*
X722523Y221315D03*
X720437Y185829D03*
X720472Y179527D03*
Y192125D03*
X711022Y182676D03*
X704724Y192125D03*
X711024D03*
X730737Y235199D03*
X724465Y224741D03*
X714620Y221041D03*
X743460Y231900D03*
X701574Y192125D03*
X707873D03*
X714173D03*
X723621D03*
Y185826D03*
Y179527D03*
X715467Y210507D03*
X725009Y213292D03*
X739852Y195915D03*
X737832Y202664D03*
X729920Y188977D03*
X739752Y199615D03*
X738416Y190551D03*
X729920Y182678D03*
X745485Y197673D03*
Y201673D03*
X740352Y180115D03*
X729920Y185827D03*
X724776Y209963D03*
X743752Y187115D03*
X742502Y182715D03*
X742252Y177015D03*
X737315Y177952D03*
X733070Y179527D03*
X720819Y209800D03*
X729246Y209941D03*
X736272Y208181D03*
X729136Y206654D03*
X738839Y206080D03*
X733565Y210184D03*
X729920Y192126D03*
X720357Y207104D03*
X714173Y198425D03*
X729921Y179527D03*
X720471Y198424D03*
X731915Y206310D03*
X738952Y184215D03*
X744052Y193784D03*
X701574Y198424D03*
X711023Y198425D03*
X704724D03*
X717322D03*
X707873Y198424D03*
X723621D03*
X704724Y201574D03*
X706737Y205505D03*
X705336Y208437D03*
X711310Y207023D03*
X714173Y201574D03*
X718330Y205172D03*
X704708Y264647D03*
X751878Y276817D03*
X749620Y273620D03*
X707574Y276558D03*
X712720Y240976D03*
X754227Y297611D03*
X739300Y287611D03*
X751693Y255540D03*
X743507Y251685D03*
X747558Y247274D03*
X759558Y241027D03*
Y247274D03*
X731300Y287611D03*
X735300D03*
X731318Y283571D03*
X735318D03*
X731155Y279636D03*
X739318Y283571D03*
X734638Y275696D03*
X751693Y259540D03*
X755693D03*
X704708Y256647D03*
Y252647D03*
X753560Y273780D03*
X704708Y260647D03*
X751133Y313984D03*
X754227Y301111D03*
X705320Y420610D03*
X735570Y424760D03*
X739680Y423900D03*
X700200Y388200D03*
Y384800D03*
X718110Y442960D03*
X708355Y454712D03*
X701120Y430620D03*
X719920Y429700D03*
X743480Y439080D03*
X706120Y441410D03*
X729870Y451300D03*
X740900Y456400D03*
X700855Y426719D03*
X761650Y89937D03*
X771610Y93040D03*
X799500Y106000D03*
X781000Y88000D03*
Y84200D03*
X788287Y86087D03*
X768250Y106300D03*
X768100Y109700D03*
X763560Y59820D03*
X767359Y82076D03*
X804320Y134300D03*
X804400Y175000D03*
X760800Y169550D03*
X769600Y164200D03*
X765200Y135750D03*
X786500Y134283D03*
X763050Y154100D03*
X761400Y160050D03*
X764600Y141500D03*
X768700Y129800D03*
X768900Y134800D03*
X760715Y197200D03*
X764550Y182900D03*
X764750Y179300D03*
X761550Y180500D03*
X786400Y179000D03*
X779200Y178650D03*
X790714Y237308D03*
X801618Y210116D03*
Y214116D03*
X786006Y283383D03*
X775486Y287316D03*
X781640Y282160D03*
X793837Y291696D03*
X805254Y263886D03*
X761484Y255581D03*
Y251581D03*
X780837Y240885D03*
X774637Y267746D03*
X770637D03*
X761638Y259635D03*
X774637Y259746D03*
Y263746D03*
X793837Y279636D03*
Y275696D03*
X780837Y267826D03*
X784837Y263891D03*
Y259951D03*
X793852Y256011D03*
Y252076D03*
X793837Y271761D03*
Y267826D03*
Y263696D03*
X774657Y255999D03*
X765638Y255635D03*
X774637Y251876D03*
X784837Y271761D03*
Y267826D03*
X793837Y287696D03*
X780837Y271761D03*
X801853Y300515D03*
X767890Y273380D03*
X763292Y287630D03*
X786610Y321340D03*
X786300Y309900D03*
X761520Y339110D03*
X765764Y326844D03*
X801728Y304572D03*
X776497Y338392D03*
X775672Y350204D03*
G54D15*
X38502Y161319D03*
X49302D03*
X43902D03*
X49302Y150519D03*
Y155919D03*
X43902Y150519D03*
Y155919D03*
X38502D03*
Y150519D03*
X108672Y138471D03*
Y132871D03*
X90672Y138471D03*
X102672D03*
X96672D03*
X84672D03*
Y132871D03*
X96672D03*
X102672D03*
X90672D03*
G54D16*
X54900Y204700D03*
X49900Y209700D03*
X59900D03*
X54900Y214700D03*
Y209700D03*
X246493Y399567D03*
X242893D03*
X257020Y390670D03*
X253420D03*
X249820D03*
X246220D03*
X256120Y395170D03*
X243120D03*
X247620D03*
X251870D03*
X242620Y390670D03*
X260893Y399567D03*
X257293D03*
X260620Y390670D03*
Y395170D03*
X253693Y399567D03*
X250093D03*
X609400Y446850D03*
X604400Y456100D03*
Y451850D03*
Y447350D03*
Y460350D03*
X609400Y450450D03*
Y454050D03*
Y457650D03*
Y461250D03*
X599503Y447123D03*
Y450723D03*
Y454323D03*
Y457923D03*
X604400Y464850D03*
X609400D03*
X599503Y461523D03*
Y465123D03*
X694400Y452900D03*
Y457400D03*
Y461900D03*
X689900Y457400D03*
Y452950D03*
X689700Y461850D03*
X698900Y457400D03*
X699000Y452950D03*
X698950Y461800D03*
G54D24*
X98425Y472441D03*
X137795D03*
G54D29*
X388189Y44095D03*
X374016D03*
X359843D03*
X345670D03*
X388189Y38583D03*
X374016D03*
X359843D03*
X345670D03*
X388189Y29922D03*
X374016D03*
X359843D03*
X345670D03*
X388189Y24410D03*
X374016D03*
X359843D03*
X345670D03*
X388189Y15748D03*
X374016D03*
X359843D03*
X345670D03*
X388189Y10237D03*
X374016D03*
X359843D03*
X345670D03*
X381103Y48819D03*
X366929D03*
X352756D03*
X338583D03*
X381103Y43307D03*
X366929D03*
X352756D03*
X338583D03*
X381103Y34646D03*
X366929D03*
X352756D03*
X338583D03*
X381103Y29134D03*
X366929D03*
X352756D03*
X338583D03*
X381103Y20473D03*
X366929D03*
X352756D03*
X338583D03*
X381103Y14961D03*
X366929D03*
X352756D03*
X338583D03*
X444882Y44095D03*
X430709D03*
X416536D03*
X402363D03*
X444882Y38583D03*
X430709D03*
X416536D03*
X402363D03*
X444882Y29922D03*
X430709D03*
X416536D03*
X402363D03*
X444882Y24410D03*
X430709D03*
X416536D03*
X402363D03*
X444882Y15748D03*
X430709D03*
X416536D03*
X402363D03*
X444882Y10237D03*
X430709D03*
X416536D03*
X402363D03*
X437796Y48819D03*
X423622D03*
X409449D03*
X395276D03*
X437796Y43307D03*
X423622D03*
X409449D03*
X395276D03*
X437796Y34646D03*
X423622D03*
X409449D03*
X395276D03*
X437796Y29134D03*
X423622D03*
X409449D03*
X395276D03*
X437796Y20473D03*
X423622D03*
X409449D03*
X395276D03*
X437796Y14961D03*
X423622D03*
X409449D03*
X395276D03*
X401575Y410039D03*
X410433D03*
X419292D03*
X404528Y412795D03*
X413386D03*
X422244D03*
X401575Y425000D03*
X410433D03*
X419292D03*
X407480Y422244D03*
X416339D03*
X425197D03*
X407480Y407284D03*
X416339D03*
X425197D03*
X404528Y427756D03*
X413386D03*
X422244D03*
X401575Y439961D03*
X410433D03*
X419292D03*
X404528Y442717D03*
X413386D03*
X422244D03*
X401575Y454921D03*
X410433D03*
X419292D03*
X404528Y457677D03*
X413386D03*
X422244D03*
X407480Y437205D03*
X416339D03*
X425197D03*
X407480Y452165D03*
X416339D03*
X425197D03*
X501575Y44095D03*
X487402D03*
X473229D03*
X459055D03*
X501575Y38583D03*
X487402D03*
X473229D03*
X459055D03*
X501575Y29922D03*
X487402D03*
X473229D03*
X459055D03*
X501575Y24410D03*
X487402D03*
X473229D03*
X459055D03*
X501575Y15748D03*
X487402D03*
X473229D03*
X459055D03*
X501575Y10237D03*
X487402D03*
X473229D03*
X459055D03*
X508662Y48819D03*
X494489D03*
X480315D03*
X466142D03*
X451969D03*
X508662Y43307D03*
X494489D03*
X480315D03*
X466142D03*
X451969D03*
X508662Y34646D03*
X494489D03*
X480315D03*
X466142D03*
X451969D03*
X508662Y29134D03*
X494489D03*
X480315D03*
X466142D03*
X451969D03*
X508662Y20473D03*
X494489D03*
X480315D03*
X466142D03*
X451969D03*
X508662Y14961D03*
X494489D03*
X480315D03*
X466142D03*
X451969D03*
X572441Y44095D03*
X558268D03*
X544095D03*
X529922D03*
X515748D03*
X572441Y38583D03*
X558268D03*
X544095D03*
X529922D03*
X515748D03*
X572441Y29922D03*
X558268D03*
X544095D03*
X529922D03*
X515748D03*
X572441Y24410D03*
X558268D03*
X544095D03*
X529922D03*
X515748D03*
X572441Y15748D03*
X558268D03*
X544095D03*
X529922D03*
X515748D03*
X572441Y10237D03*
X558268D03*
X544095D03*
X529922D03*
X515748D03*
X565355Y48819D03*
X551181D03*
X537008D03*
X522835D03*
X565355Y43307D03*
X551181D03*
X537008D03*
X522835D03*
X565355Y34646D03*
X551181D03*
X537008D03*
X522835D03*
X565355Y29134D03*
X551181D03*
X537008D03*
X522835D03*
X565355Y20473D03*
X551181D03*
X537008D03*
X522835D03*
X565355Y14961D03*
X551181D03*
X537008D03*
X522835D03*
X586614Y44095D03*
Y38583D03*
Y29922D03*
Y24410D03*
Y15748D03*
Y10237D03*
X579528Y48819D03*
Y43307D03*
Y34646D03*
Y29134D03*
Y20473D03*
Y14961D03*
X758267Y44095D03*
X744094D03*
X729921D03*
X715748D03*
X758267Y38583D03*
X744094D03*
X729921D03*
X715748D03*
X758267Y29922D03*
X744094D03*
X729921D03*
X715748D03*
X758267Y24410D03*
X744094D03*
X729921D03*
X715748D03*
X758267Y15748D03*
X744094D03*
X729921D03*
X715748D03*
X758267Y10237D03*
X744094D03*
X729921D03*
X715748D03*
X751181Y48819D03*
X737007D03*
X722834D03*
X708661D03*
X751181Y43307D03*
X737007D03*
X722834D03*
X708661D03*
X751181Y34646D03*
X737007D03*
X722834D03*
X708661D03*
X751181Y29134D03*
X737007D03*
X722834D03*
X708661D03*
X751181Y20473D03*
X737007D03*
X722834D03*
X708661D03*
X751181Y14961D03*
X737007D03*
X722834D03*
X708661D03*
G54D35*
X410236Y419291D03*
Y404331D03*
Y449212D03*
Y434252D03*
G54D18*
X37402Y499724D03*
X789370D03*
G54D22*
X128580Y170810D03*
X122984Y170984D03*
X123200Y175800D03*
X125741Y166309D03*
X128459Y175658D03*
X198557Y153196D03*
X177850Y324800D03*
X174995Y353588D03*
Y358388D03*
X165195D03*
X169995D03*
Y353588D03*
X197718Y350937D03*
Y355859D03*
X157650Y418100D03*
X160400Y422900D03*
X160550Y414100D03*
X177468Y417900D03*
X160400Y427700D03*
Y432500D03*
X176311Y445493D03*
X176423Y440472D03*
X177421Y432909D03*
X177532Y426134D03*
X200266Y565366D03*
X195266D03*
X190266D03*
X185266D03*
X180266D03*
X222800Y204600D03*
X227600D03*
X222800Y219000D03*
X227600D03*
X222800Y214200D03*
X227600D03*
X222800Y209400D03*
X227600D03*
X222490Y235373D03*
X227290D03*
X222246Y229952D03*
X227046D03*
X222800Y223800D03*
X227600D03*
X222460Y240264D03*
X227260D03*
X254300Y357732D03*
X222818Y364806D03*
X222909Y371864D03*
X223000Y378246D03*
X246700Y418600D03*
X209052Y470198D03*
X213700Y448450D03*
X208900D03*
X203000Y451300D03*
X204252Y470198D03*
X204364Y478917D03*
X209164D03*
X205266Y565366D03*
X210266D03*
X215266D03*
X220266D03*
X225266D03*
X230266D03*
X235266D03*
X240266D03*
X245266D03*
X250266D03*
X255266D03*
X260266D03*
X287300Y173000D03*
X292100D03*
X295650Y169554D03*
X295801Y210294D03*
X292600Y214500D03*
X287800D03*
X295879Y255540D03*
X291079D03*
X286279D03*
X276070Y395357D03*
X265266Y565366D03*
X270266D03*
X275266D03*
X280266D03*
X285266D03*
X290266D03*
X295266D03*
X300266D03*
X305266D03*
X310266D03*
X315266D03*
X320266D03*
X325266D03*
X350586Y495815D03*
X355523Y495025D03*
X360461Y494236D03*
X365398Y493446D03*
X370335Y492656D03*
X375272Y491866D03*
X380210Y491077D03*
X385169Y490563D03*
X329156Y545492D03*
Y540492D03*
Y535492D03*
Y530492D03*
Y525492D03*
Y520492D03*
Y515492D03*
Y560492D03*
Y555492D03*
Y550492D03*
X405169Y490563D03*
X410169D03*
X415169D03*
X420169D03*
X425169D03*
X430169D03*
X435169D03*
X440169D03*
X445146Y490850D03*
X450083Y491640D03*
X390169Y490563D03*
X395169D03*
X400169D03*
X490877Y176547D03*
X510427Y176431D03*
X500302Y176489D03*
X490877Y189047D03*
Y185047D03*
Y180547D03*
X510427Y188931D03*
Y184931D03*
Y180431D03*
X500302Y188989D03*
Y184989D03*
Y180489D03*
X505500Y464400D03*
Y469200D03*
Y474000D03*
X509500Y450800D03*
Y446000D03*
Y441200D03*
X469832Y494799D03*
X474769Y495589D03*
X455020Y492430D03*
X459958Y493219D03*
X464895Y494009D03*
X497636Y515532D03*
Y520532D03*
Y525532D03*
Y530532D03*
Y535532D03*
Y540532D03*
Y545532D03*
Y550532D03*
Y555532D03*
Y560532D03*
X502550Y565366D03*
X507550D03*
X512550D03*
X520552Y176373D03*
X557500Y231900D03*
X553500D03*
X549000D03*
X545000D03*
X520552Y188873D03*
Y184873D03*
Y180373D03*
X554717Y255796D03*
X550717D03*
X546217D03*
X542217D03*
X554975Y248209D03*
X550975D03*
X546475D03*
X542475D03*
X555865Y240638D03*
X551865D03*
X547365D03*
X543365D03*
X570234Y298026D03*
X572634Y293526D03*
X571300Y414800D03*
X567200Y407700D03*
X572062Y384378D03*
X527742Y425481D03*
X522942D03*
X518142D03*
X527742Y432481D03*
X522942D03*
X518142D03*
X529500Y471500D03*
X551400Y437800D03*
X545900D03*
X539800Y437900D03*
X517550Y565366D03*
X522550D03*
X527550D03*
X532550D03*
X537550D03*
X542550D03*
X547550D03*
X552550D03*
X557550D03*
X562550D03*
X567550D03*
X572550D03*
X589706Y174031D03*
X586081Y158407D03*
X585145Y162809D03*
X595402Y149579D03*
X594466Y153981D03*
X588070Y138220D03*
X587134Y142622D03*
X577699Y123469D03*
X576868Y127381D03*
X575932Y131783D03*
X575101Y135695D03*
X582554Y116361D03*
X589135Y214107D03*
X588199Y218509D03*
X585010Y198483D03*
X584074Y202885D03*
X580885Y182859D03*
X579949Y187261D03*
X588770Y178433D03*
X575134Y298026D03*
X577534Y293526D03*
X580034Y298026D03*
X580900Y414800D03*
X576100D03*
X576862Y384378D03*
X581087Y379569D03*
X576287D03*
X581692Y384378D03*
X628113Y428617D03*
X623313D03*
X618513D03*
X613713D03*
X605534Y480027D03*
X635000Y427784D03*
X619600Y446100D03*
X629200D03*
X624400D03*
X577550Y565366D03*
X582550D03*
X587550D03*
X592550D03*
X597550D03*
X602550D03*
X607550D03*
X612550D03*
X617550D03*
X622550D03*
X627550D03*
X632550D03*
X655964Y52248D03*
X675136Y268500D03*
X637705Y298765D03*
X642705D03*
X659977Y323082D03*
X664731Y324099D03*
X637705Y303765D03*
X642705D03*
X665520Y307707D03*
Y312507D03*
X654642D03*
X654488Y317417D03*
X660100Y307500D03*
X654642Y307707D03*
X665478Y317527D03*
X684400Y400100D03*
X694950Y477850D03*
Y473050D03*
X688500Y484400D03*
X639120Y462230D03*
X688500Y488600D03*
X637550Y565366D03*
X642550D03*
X647550D03*
X652550D03*
X657550D03*
X662550D03*
X667550D03*
X672550D03*
X677550D03*
X682550D03*
X687550D03*
X692550D03*
X697550D03*
X742200Y340800D03*
Y345600D03*
X737400Y340800D03*
Y345600D03*
X732600Y331200D03*
Y336000D03*
Y340800D03*
Y355200D03*
Y350400D03*
Y345600D03*
X701100Y315900D03*
X705900D03*
X701100Y311100D03*
X705900D03*
Y306300D03*
X701100D03*
X704115Y414466D03*
Y409666D03*
Y404866D03*
Y400066D03*
X705900Y386900D03*
X711000Y395100D03*
X710900Y386800D03*
X706000Y395100D03*
X725247Y458974D03*
X724422Y464139D03*
X724400Y485200D03*
Y480400D03*
Y475600D03*
X740900Y476400D03*
Y469400D03*
Y461900D03*
X704340Y468062D03*
X705400Y477400D03*
X724400Y490200D03*
X702550Y565366D03*
X707550D03*
X712550D03*
X717550D03*
X722550D03*
X727550D03*
X732550D03*
X737550D03*
X742550D03*
X747550D03*
X752550D03*
X757550D03*
X771083Y211784D03*
X821272Y424340D03*
Y419340D03*
Y414340D03*
Y409340D03*
Y484340D03*
Y479340D03*
Y474340D03*
Y469340D03*
Y464340D03*
Y459340D03*
Y454340D03*
Y449340D03*
Y444340D03*
Y439340D03*
Y434340D03*
Y429340D03*
Y504340D03*
Y509340D03*
Y514340D03*
Y519340D03*
Y524340D03*
Y529340D03*
Y549340D03*
Y544340D03*
Y539340D03*
Y534340D03*
Y499340D03*
Y494340D03*
Y489340D03*
X762550Y565366D03*
X767550D03*
X772550D03*
X777550D03*
X782550D03*
X787550D03*
X792550D03*
X797550D03*
X802550D03*
X807550D03*
X812550D03*
X817550D03*
X821272Y559340D03*
Y554340D03*
G54D32*
X425197Y236220D03*
X421258Y232283D03*
X448818Y232284D03*
X440944D03*
X433070D03*
X433071Y224410D03*
X440945D03*
X448819D03*
X397638Y232284D03*
X389764Y204725D03*
Y220473D03*
Y208662D03*
Y228347D03*
X409449Y236221D03*
X393701Y228347D03*
Y216536D03*
Y212599D03*
X397638D03*
X401575D03*
X393701Y220473D03*
X397638Y200788D03*
X405512D03*
X413386D03*
X421260D03*
X429134D03*
X437008D03*
X444882D03*
X409449Y212599D03*
Y224410D03*
X417323Y212599D03*
X425197D03*
X433071D03*
X440945D03*
X448819D03*
X425197Y224410D03*
X417323D03*
X413386D03*
X397638D03*
X389000Y236100D03*
X401575Y236221D03*
X405512D03*
X417322D03*
X409449Y220473D03*
Y216536D03*
X413386Y220473D03*
Y216536D03*
X417323Y220473D03*
Y216536D03*
X421260Y220473D03*
Y216536D03*
X425197Y220473D03*
Y216536D03*
X429134Y220473D03*
Y216536D03*
X433071Y220473D03*
Y216536D03*
X437008Y220473D03*
Y216536D03*
X440945Y220473D03*
Y216536D03*
X444882Y220473D03*
Y216536D03*
X448819Y220473D03*
Y216536D03*
X409449Y204725D03*
Y200788D03*
X413386Y208662D03*
Y204725D03*
X417323D03*
Y200788D03*
X421260Y208662D03*
Y204725D03*
X425197D03*
Y200788D03*
X429134Y208662D03*
Y204725D03*
X433071D03*
Y200788D03*
X437008Y208662D03*
Y204725D03*
X440945D03*
Y200788D03*
X444882Y208662D03*
Y204725D03*
X448819D03*
Y200788D03*
X389764Y216536D03*
Y212599D03*
X397638Y220473D03*
Y216536D03*
X401575Y220473D03*
Y216536D03*
X405512Y220473D03*
Y216536D03*
X393701Y204725D03*
Y200788D03*
X397638Y208662D03*
Y204725D03*
X401575D03*
Y200788D03*
X405512Y208662D03*
Y204725D03*
X401575Y232284D03*
X401727Y228641D03*
X405512Y232284D03*
X413386D03*
X405512Y228347D03*
X409449Y259843D03*
X425197Y291339D03*
X433071Y295276D03*
Y299213D03*
Y291339D03*
X448819Y287403D03*
X448818Y291339D03*
Y295276D03*
X437008Y299213D03*
Y291339D03*
X448818Y299214D03*
X425196Y283466D03*
X433070Y279528D03*
X433071Y275591D03*
X433070Y255905D03*
X437057Y279414D03*
X397638Y240158D03*
Y295276D03*
X405512D03*
X397638Y271654D03*
X409449Y267717D03*
X397638Y287402D03*
X405512D03*
X397638Y279528D03*
X409449Y275591D03*
X397638Y259843D03*
X405512D03*
Y255906D03*
X389764Y251969D03*
X393701D03*
X397638D03*
X409449Y244095D03*
Y255906D03*
X417323Y299213D03*
X421260Y291339D03*
X425197Y259843D03*
X417323Y267717D03*
X429134Y271654D03*
X417323Y275591D03*
X429134Y248032D03*
X425197Y255906D03*
X417323D03*
X413386Y259843D03*
X429134Y279528D03*
X421260D03*
X433071Y240158D03*
Y248032D03*
X448819Y240158D03*
X440945D03*
X444882Y279529D03*
X448819Y248032D03*
X440945D03*
X448818Y259843D03*
Y267718D03*
X440944D03*
X433071Y263781D03*
X440944Y259843D03*
X429134Y295277D03*
Y299214D03*
X437007Y287402D03*
X429134Y291340D03*
X421260Y259843D03*
X429134Y263781D03*
X421260Y255906D03*
X425197Y299213D03*
X429134Y287403D03*
X417323Y259843D03*
X413386Y255906D03*
X440945Y295276D03*
Y299213D03*
Y291339D03*
Y287402D03*
X437008Y295276D03*
X429134Y251969D03*
X417323D03*
X413386Y248032D03*
X405512D03*
X421260Y251969D03*
X405512Y244095D03*
X401575D03*
X413386D03*
X417323Y248032D03*
X401575Y240158D03*
X405512D03*
X433070Y287402D03*
X413387Y240158D03*
X421260Y248032D03*
X417323Y244095D03*
X413386Y251969D03*
X401575Y248032D03*
X421260Y295277D03*
X448819Y244095D03*
X440945D03*
X433071D03*
X421259Y240158D03*
X421260Y244095D03*
X417323Y240157D03*
X421260Y299214D03*
X425197Y295276D03*
X413386Y311025D03*
X425197Y318898D03*
Y303150D03*
X429134Y314961D03*
Y311024D03*
X448819Y307088D03*
X448818Y311024D03*
Y303151D03*
X444882Y314961D03*
Y318898D03*
X433071Y314961D03*
X431102Y331263D03*
X397638Y326772D03*
X409449D03*
X397638Y318898D03*
X409449D03*
Y314961D03*
X397638Y311024D03*
X409449D03*
X417323Y326772D03*
Y318898D03*
X425197Y311024D03*
X433071D03*
X397638Y303150D03*
X405512D03*
X413386Y307087D03*
X440945Y318898D03*
X448819D03*
X417323Y307087D03*
Y303150D03*
X429134Y303151D03*
X425197Y314961D03*
X417323Y311024D03*
X429134Y318898D03*
X442800Y330300D03*
X446200Y327400D03*
X440945Y303150D03*
Y311024D03*
Y307087D03*
X444881Y322835D03*
X442913Y327204D03*
X440944Y322835D03*
X438976Y327204D03*
X437008Y318898D03*
Y314961D03*
Y311024D03*
Y303150D03*
Y307087D03*
X433071Y318898D03*
X421260Y326772D03*
X421259Y322835D03*
X421260Y318898D03*
Y314961D03*
X417322Y322835D03*
X413386Y314962D03*
X421260Y307088D03*
X433071Y303150D03*
X421260Y303151D03*
X456693Y232284D03*
X464567D03*
X472441D03*
X480315D03*
X456693Y200788D03*
X464567D03*
X492126Y208662D03*
Y204725D03*
X500000D03*
X472441Y200788D03*
X480315D03*
X488189D03*
X492126D03*
X460630Y212599D03*
X468504D03*
X492126Y216536D03*
X476378Y212599D03*
X484252D03*
X492126D03*
X503937D03*
X507874Y208662D03*
X503937Y204725D03*
X507874D03*
X503937Y236221D03*
Y228347D03*
X492126Y220473D03*
X503937D03*
X511811Y208662D03*
X507874Y200788D03*
X511811D03*
X472441Y224410D03*
X464567D03*
X456693D03*
X480315D03*
X492126D03*
X488189D03*
X492126Y232284D03*
Y236221D03*
X500000Y200788D03*
X503937D03*
X456693Y220473D03*
Y216536D03*
X460630Y220473D03*
Y216536D03*
X464567Y220473D03*
Y216536D03*
X468504Y220473D03*
Y216536D03*
X472441Y220473D03*
Y216536D03*
X476378Y220473D03*
Y216536D03*
X480315Y220473D03*
Y216536D03*
X484252Y220473D03*
Y216536D03*
X488189Y220473D03*
Y216536D03*
X500000Y208662D03*
X503937D03*
X496063Y212599D03*
X500000D03*
X496063Y216536D03*
X500000D03*
X496063Y220473D03*
X500000D03*
X496063Y224410D03*
X500000D03*
X496063Y228347D03*
X500000D03*
X496063Y232284D03*
X500000D03*
X496063Y236221D03*
X500000D03*
X456693Y208662D03*
Y204725D03*
X460630D03*
Y200788D03*
X464567Y208662D03*
Y204725D03*
X468504D03*
Y200788D03*
X472441Y208662D03*
Y204725D03*
X476378D03*
Y200788D03*
X480315Y208662D03*
Y204725D03*
X484252D03*
Y200788D03*
X488189Y208662D03*
Y204725D03*
X468504Y299214D03*
X472442Y287402D03*
X480315Y295276D03*
X484252Y295277D03*
X476378Y291339D03*
X452755Y287402D03*
Y291340D03*
Y295277D03*
X464567Y299214D03*
X456693Y279528D03*
Y267718D03*
X464567D03*
X472441Y295276D03*
X503937Y251969D03*
Y244095D03*
Y271654D03*
Y259843D03*
Y287402D03*
Y279528D03*
Y295276D03*
X488189Y287402D03*
X492126Y291339D03*
X488189D03*
X472441Y240158D03*
X456693Y259843D03*
X464567Y240158D03*
X456693D03*
X480315Y267717D03*
Y271654D03*
Y275591D03*
Y279528D03*
Y283465D03*
X492126Y267717D03*
X488189Y271654D03*
X492126Y275591D03*
X488189Y279528D03*
X492126Y283465D03*
X480315Y259843D03*
Y240158D03*
Y244095D03*
Y248032D03*
Y251969D03*
Y255906D03*
X488189Y259843D03*
X492126Y240158D03*
X488189D03*
X492126Y248032D03*
X488189D03*
Y255906D03*
X452757Y279529D03*
X464567D03*
X472441Y275591D03*
Y267717D03*
Y283465D03*
Y259843D03*
Y251969D03*
X456693Y248032D03*
X464567D03*
Y259843D03*
X472441Y291339D03*
X464568Y287402D03*
X460630Y299213D03*
X480316Y287403D03*
X484252Y291340D03*
Y287402D03*
X488189Y295276D03*
X456694D03*
X496063Y255906D03*
X500000D03*
X496063Y259843D03*
X500000D03*
X496063Y267717D03*
X500000D03*
X496063Y240158D03*
X500000D03*
X496063Y244095D03*
X500000D03*
X496063Y271654D03*
X500000D03*
X496063Y248032D03*
X500000D03*
X496063Y251969D03*
X500000D03*
X496063Y275591D03*
X500000D03*
X496063Y279528D03*
X500000D03*
X496063Y283465D03*
X500000D03*
X496063Y287402D03*
X500000D03*
X507874Y255906D03*
X511811D03*
Y259843D03*
X507874Y267717D03*
X511811D03*
X507874Y240158D03*
X511811D03*
Y244095D03*
Y271654D03*
X507874Y248032D03*
X511811D03*
Y251969D03*
X507874Y275591D03*
X511811D03*
Y279528D03*
X507874Y283465D03*
X511811D03*
Y287402D03*
X480315Y291339D03*
X496063Y299213D03*
X500000D03*
X496063Y291339D03*
X500000D03*
X496063Y295276D03*
X500000D03*
X476378Y267717D03*
Y275591D03*
Y259843D03*
Y251969D03*
X472441Y244095D03*
X464567D03*
X456693D03*
Y291339D03*
X460630D03*
X500001Y314961D03*
X503937Y318898D03*
X488189Y307087D03*
X492126Y311024D03*
X460630Y307087D03*
X456693D03*
X460630Y311024D03*
X462599Y327204D03*
X456693Y311024D03*
Y314961D03*
X452755Y307087D03*
Y303150D03*
X456693Y318898D03*
X472441Y303150D03*
X460630Y318898D03*
X468504D03*
X456693Y303150D03*
X476378Y318898D03*
X484252D03*
X492126D03*
X500000D03*
X496063Y307087D03*
X480315Y303150D03*
X492126D03*
X507874Y318898D03*
Y307087D03*
X511811D03*
X503937Y303150D03*
X484252D03*
X496063Y318898D03*
X488189Y311024D03*
X484252Y307087D03*
X496063Y314961D03*
X476378Y311024D03*
X472441Y307087D03*
X488189Y303150D03*
X500000Y307088D03*
X503937Y311024D03*
X468504Y303151D03*
X460630Y303150D03*
X464567Y303151D03*
X503937Y307087D03*
X507874Y311024D03*
X464567Y307088D03*
X468505D03*
X472441Y314961D03*
X492126Y307087D03*
X496063Y311024D03*
X464567Y311025D03*
Y318898D03*
X472441D03*
X496063Y303150D03*
X500000D03*
X470473Y327204D03*
X468504Y311024D03*
X488189Y322835D03*
X517000Y226370D03*
Y218500D03*
Y234252D03*
X517500Y297218D03*
X518647Y288943D03*
X515748Y240158D03*
Y267717D03*
Y255906D03*
Y248032D03*
Y283465D03*
Y275591D03*
Y259843D03*
Y244095D03*
Y271654D03*
Y251969D03*
Y279528D03*
Y287402D03*
Y318898D03*
Y307087D03*
X666928Y144880D03*
X660630Y122834D03*
X660629Y119685D03*
X663779Y122834D03*
Y119685D03*
X670079Y122835D03*
X670078Y119685D03*
X673229Y122835D03*
X673228Y119685D03*
X679528Y122835D03*
X679527Y119685D03*
X682678Y122835D03*
X682677Y119685D03*
X688977Y122835D03*
X688976Y119685D03*
X692126Y122835D03*
Y119686D03*
G54D25*
X145669Y25708D03*
Y47362D03*
Y19803D03*
Y31614D03*
Y41456D03*
Y53267D03*
G54D23*
X140000Y204950D03*
X201400Y174400D03*
X192400D03*
X196900D03*
X179800Y133500D03*
X175800Y129500D03*
X179800D03*
X175800Y133500D03*
X170900Y160500D03*
X151500D03*
X156300D03*
X161100D03*
X165900D03*
X192400Y191600D03*
X196900D03*
X201400D03*
X192400Y187300D03*
X196900D03*
X201400D03*
Y178700D03*
X192400Y183000D03*
X196900D03*
X201400D03*
X192400Y178700D03*
X196900D03*
X151500Y205000D03*
X156300D03*
X161100D03*
X165900D03*
X170900D03*
X178450Y203150D03*
X144800Y204950D03*
X268000Y165962D03*
X268064Y171792D03*
Y184062D03*
X268118Y191305D03*
X268000Y196800D03*
Y178062D03*
X425196Y240158D03*
X476379Y287402D03*
X468505D03*
X631864Y51848D03*
X656300Y20100D03*
X660200Y20200D03*
X694365Y98458D03*
Y86958D03*
X686279Y98494D03*
Y86994D03*
X678225Y98496D03*
Y86996D03*
X670146Y98505D03*
Y87005D03*
X662047Y98539D03*
Y87039D03*
X654037Y98708D03*
Y87208D03*
X655532Y425245D03*
X658032Y420245D03*
X653032D03*
X659000Y428900D03*
X652200Y429100D03*
X710378Y100399D03*
Y88899D03*
X702391Y98510D03*
Y87010D03*
X742200Y380400D03*
Y370800D03*
Y375600D03*
G54D11*
X15364Y5500D03*
X10364D03*
X5500Y10384D03*
Y15384D03*
Y20384D03*
Y25384D03*
Y30384D03*
Y35384D03*
Y40384D03*
Y45384D03*
Y50384D03*
Y55384D03*
Y60384D03*
Y65384D03*
Y70384D03*
Y75384D03*
Y80384D03*
Y85384D03*
Y90384D03*
Y95384D03*
Y100384D03*
Y105384D03*
Y110384D03*
Y115384D03*
Y120384D03*
Y125384D03*
Y130384D03*
Y135384D03*
Y140384D03*
Y145384D03*
Y150384D03*
Y155384D03*
Y160384D03*
Y165384D03*
Y170384D03*
Y175384D03*
Y180384D03*
Y185384D03*
Y190384D03*
Y195384D03*
Y200384D03*
Y205384D03*
Y210384D03*
Y215384D03*
Y220384D03*
Y225384D03*
Y230384D03*
Y235384D03*
Y240384D03*
Y245384D03*
Y250384D03*
Y255384D03*
Y260384D03*
Y265384D03*
Y270384D03*
Y275384D03*
Y280384D03*
Y285384D03*
Y290384D03*
Y295384D03*
Y300384D03*
Y305384D03*
Y310384D03*
Y315384D03*
Y320384D03*
Y325384D03*
Y330384D03*
Y335384D03*
Y340384D03*
Y345384D03*
Y350384D03*
Y355384D03*
Y360384D03*
Y365384D03*
Y370384D03*
Y375384D03*
Y380384D03*
Y385384D03*
Y390384D03*
Y395384D03*
Y400384D03*
Y405384D03*
Y410384D03*
Y415384D03*
Y420384D03*
Y425384D03*
Y430384D03*
Y435384D03*
Y440384D03*
Y445384D03*
Y450384D03*
Y455384D03*
Y460384D03*
Y465384D03*
Y470384D03*
Y475384D03*
Y480384D03*
Y485384D03*
Y530384D03*
Y525384D03*
Y520384D03*
Y515384D03*
Y510384D03*
Y505384D03*
Y490384D03*
Y495384D03*
Y500384D03*
Y535384D03*
Y540384D03*
Y545384D03*
Y550384D03*
Y555384D03*
Y560384D03*
X10266Y565366D03*
X15266D03*
X75364Y5500D03*
X70364D03*
X65364D03*
X60364D03*
X55364D03*
X50364D03*
X45364D03*
X40364D03*
X35364D03*
X30364D03*
X25364D03*
X20364D03*
X21910Y217500D03*
X22250Y223500D03*
X33759Y274180D03*
X37830D03*
X23100Y292200D03*
Y287700D03*
X56026Y256117D03*
X37049Y302949D03*
X23100Y318500D03*
Y314000D03*
X52450Y333850D03*
X31450Y334050D03*
X74150Y334250D03*
X57350Y387800D03*
X46900Y378233D03*
X26100Y378352D03*
X69300Y378800D03*
X31240Y393440D03*
X49700Y391000D03*
X54040Y399390D03*
X20266Y565366D03*
X25266D03*
X30266D03*
X35266D03*
X40266D03*
X45266D03*
X50266D03*
X55266D03*
X60266D03*
X65266D03*
X70266D03*
X75266D03*
X95364Y5500D03*
X90364D03*
X85364D03*
X80364D03*
X81000Y291700D03*
X80896Y286695D03*
X95245Y334043D03*
X94080Y448470D03*
X94488Y489888D03*
X80266Y565366D03*
X85266D03*
X90266D03*
X95266D03*
X100266D03*
X105266D03*
X110266D03*
X115266D03*
X120266D03*
X125266D03*
X130266D03*
X135266D03*
X158267Y25708D03*
Y47362D03*
Y53267D03*
Y41456D03*
Y31614D03*
Y19803D03*
X200364Y5500D03*
X195364D03*
X190364D03*
X185364D03*
X180364D03*
X175364D03*
X170364D03*
X191000Y110000D03*
X192830Y170500D03*
X197630D03*
X192830Y165700D03*
X197630D03*
X192830Y160900D03*
X197630D03*
X196963Y122029D03*
X184600Y137400D03*
X195400Y147200D03*
X195500Y142400D03*
X191900Y196100D03*
X196900D03*
X201700D03*
X196900Y200900D03*
X191900D03*
X196900Y205700D03*
X191900D03*
X196900Y210500D03*
X191900D03*
X201700Y205700D03*
Y200900D03*
X158067Y378857D03*
X175266Y565366D03*
X140266D03*
X145266D03*
X150266D03*
X155266D03*
X160266D03*
X165266D03*
X170266D03*
X260364Y5500D03*
X255364D03*
X250364D03*
X245364D03*
X240364D03*
X235364D03*
X230364D03*
X225364D03*
X220364D03*
X215364D03*
X210364D03*
X205364D03*
X245250Y98250D03*
X223994Y63225D03*
X261499Y55353D03*
X257499D03*
X222700Y149300D03*
X227500D03*
X222700Y144500D03*
X227500D03*
X222700Y139700D03*
X227500D03*
X222700Y158900D03*
X227500D03*
X222700Y154100D03*
X227500D03*
X202430Y170500D03*
Y165700D03*
Y160900D03*
X253600Y139500D03*
Y134700D03*
X251800Y153600D03*
Y144000D03*
Y148800D03*
X258400Y134700D03*
Y139500D03*
X263200Y134700D03*
Y139500D03*
X253600Y230500D03*
Y225700D03*
Y220900D03*
X258400Y230500D03*
Y225700D03*
Y220900D03*
X263200Y230500D03*
Y225700D03*
Y220900D03*
X249204Y244103D03*
X231700Y320100D03*
X249775Y320167D03*
X214700Y320200D03*
X212589Y494694D03*
X220589D03*
X216589Y489694D03*
X208589D03*
X224589D03*
X312840Y42398D03*
X325378Y50351D03*
Y35351D03*
X310065Y32397D03*
X325364Y5500D03*
X320364D03*
X315364D03*
X310364D03*
X305364D03*
X300364D03*
X295364D03*
X290364D03*
X285364D03*
X280364D03*
X275364D03*
X270364D03*
X265364D03*
X270000Y29000D03*
Y33500D03*
Y38000D03*
Y42500D03*
X267188Y55192D03*
X285361Y78015D03*
X281761D03*
X289161Y58068D03*
X277514D03*
X295960Y148987D03*
Y154387D03*
X308907Y171800D03*
Y166400D03*
Y161000D03*
X287000Y117600D03*
Y125000D03*
X285500Y130400D03*
X290300D03*
X295100D03*
X272800Y168000D03*
Y172800D03*
Y134700D03*
X268000Y158700D03*
Y153900D03*
Y134700D03*
Y139500D03*
Y144300D03*
Y149100D03*
X296200Y195900D03*
Y190500D03*
X308907Y215200D03*
Y220600D03*
Y226000D03*
Y231400D03*
Y236800D03*
Y209800D03*
Y188200D03*
Y199000D03*
Y204400D03*
Y177200D03*
Y193600D03*
Y182800D03*
X296400Y237950D03*
Y232550D03*
X272800Y177600D03*
X268000Y235300D03*
Y230500D03*
Y225700D03*
Y220900D03*
Y216000D03*
Y211200D03*
Y206400D03*
Y201600D03*
X308907Y242200D03*
X266404Y249707D03*
X268000Y244900D03*
Y240100D03*
X280800Y325000D03*
X290750D03*
X280217Y350927D03*
X269365Y320351D03*
X388189Y48426D03*
X374016D03*
X359843D03*
X345670D03*
X388189Y34252D03*
X374016D03*
X359843D03*
X345670D03*
X388189Y20079D03*
X374016D03*
X359843D03*
X345670D03*
X388189Y5906D03*
X374016D03*
X359843D03*
X345670D03*
X381103Y38977D03*
X366929D03*
X352756D03*
X338583D03*
X381103Y24804D03*
X366929D03*
X352756D03*
X338583D03*
X381103Y53150D03*
X366929D03*
X352756D03*
X338583D03*
X330364Y5500D03*
X346700Y296333D03*
Y291533D03*
X375148Y337184D03*
X382600Y337200D03*
X344000Y316000D03*
X374432Y316002D03*
X338000Y421000D03*
X444882Y48426D03*
X430709D03*
X416536D03*
X402363D03*
X444882Y34252D03*
X430709D03*
X416536D03*
X402363D03*
X444882Y20079D03*
X430709D03*
X416536D03*
X402363D03*
X444882Y5906D03*
X430709D03*
X416536D03*
X402363D03*
X437796Y38977D03*
X423622D03*
X409449D03*
X395276D03*
X437796Y24804D03*
X423622D03*
X409449D03*
X395276D03*
X437796Y53150D03*
X423622D03*
X409449D03*
X395276D03*
X433070Y236221D03*
X440944D03*
X448818D03*
X433070Y228347D03*
X440944D03*
X448818D03*
X405512Y212599D03*
X393701Y208662D03*
X401575D03*
X409449D03*
X417323D03*
X425197D03*
X433071D03*
X440945D03*
X448819D03*
X413386Y212599D03*
X421260D03*
X429134D03*
X437008D03*
X444882D03*
X409449Y232284D03*
X397638Y236221D03*
Y228347D03*
X437008Y275591D03*
X444882D03*
X429134Y255906D03*
X433071Y283465D03*
X425197Y287402D03*
X444882D03*
X440945Y283465D03*
X448819D03*
X444882Y299213D03*
X409449Y240158D03*
Y248032D03*
X397638Y244095D03*
X413386Y326772D03*
X416822Y347133D03*
X412381Y347149D03*
X435000Y347800D03*
X441000D03*
X433500Y337500D03*
X426464Y347078D03*
X397000Y337000D03*
X425197Y307087D03*
X417323Y314961D03*
X433071Y307087D03*
X448819Y314961D03*
X440945D03*
X501575Y48426D03*
X487402D03*
X473229D03*
X459055D03*
X501575Y34252D03*
X487402D03*
X473229D03*
X459055D03*
X501575Y20079D03*
X487402D03*
X473229D03*
X459055D03*
X501575Y5906D03*
X487402D03*
X473229D03*
X459055D03*
X508662Y38977D03*
X494489D03*
X480315D03*
X466142D03*
X451969D03*
X508662Y24804D03*
X494489D03*
X480315D03*
X466142D03*
X451969D03*
X508662Y53150D03*
X494489D03*
X480315D03*
X466142D03*
X451969D03*
X456693Y236221D03*
X464567D03*
X472441D03*
X460630Y208662D03*
X468504D03*
X484252D03*
X476378D03*
X496063D03*
X456693Y212599D03*
X464567D03*
X503937Y216536D03*
X472441Y212599D03*
X480315D03*
X488189D03*
X507874D03*
Y236221D03*
X503937Y232284D03*
X507874Y228347D03*
X503937Y224410D03*
X507874Y220473D03*
X472441Y228347D03*
X464567D03*
X456693D03*
X480315D03*
X484252Y236221D03*
X488189Y232284D03*
X503937Y255906D03*
X507874Y251969D03*
X503937Y248032D03*
X507874Y244095D03*
X503937Y240158D03*
X507874Y271654D03*
X503937Y267717D03*
X507874Y259843D03*
Y287402D03*
X503937Y283465D03*
X507874Y279528D03*
X503937Y275591D03*
Y299213D03*
X507874Y295276D03*
X503937Y291339D03*
X492126Y287402D03*
X484252Y271654D03*
Y279528D03*
X488189Y267717D03*
Y275591D03*
X492126Y271654D03*
Y279528D03*
X488189Y283465D03*
X484252Y259843D03*
Y251969D03*
Y244095D03*
X492126Y259843D03*
Y251969D03*
Y244095D03*
X456693Y255906D03*
X472441Y299213D03*
X480315D03*
X488189D03*
X456693Y287402D03*
X460630Y283465D03*
X468504D03*
X456693Y299213D03*
X507874Y303150D03*
X476500Y347650D03*
X498138Y348500D03*
X506200Y358809D03*
X493200Y358800D03*
X498700Y359209D03*
X452600Y332700D03*
X484252Y314961D03*
X476378D03*
X468504D03*
X507874D03*
X492126D03*
X460630D03*
X473900Y371800D03*
X485100Y363400D03*
X572441Y48426D03*
X558268D03*
X544095D03*
X529922D03*
X515748D03*
X572441Y34252D03*
X558268D03*
X544095D03*
X529922D03*
X515748D03*
X572441Y20079D03*
X558268D03*
X544095D03*
X529922D03*
X515748D03*
X572441Y5906D03*
X558268D03*
X544095D03*
X529922D03*
X515748D03*
X565355Y38977D03*
X551181D03*
X537008D03*
X522835D03*
X565355Y24804D03*
X551181D03*
X537008D03*
X522835D03*
X565355Y53150D03*
X551181D03*
X537008D03*
X522835D03*
X547225Y357997D03*
X538225D03*
X555697Y356565D03*
X514000Y359209D03*
X514138Y348500D03*
X518138Y348350D03*
X525438Y350500D03*
X516500Y313000D03*
X586614Y48426D03*
Y34252D03*
Y20079D03*
Y5906D03*
X579528Y38977D03*
Y24804D03*
Y53150D03*
X591446Y6545D03*
X596446D03*
X601446D03*
X606446D03*
X611446D03*
X616446D03*
X621446D03*
X636446D03*
X631446D03*
X626446D03*
X635942Y97351D03*
X576797Y113877D03*
X598600Y247800D03*
Y253100D03*
X598023Y383081D03*
X632150Y389100D03*
X581020Y471890D03*
X588030Y430795D03*
X641446Y6545D03*
X646446D03*
X651446D03*
X652551Y40716D03*
X696446Y6545D03*
X691446D03*
X661446D03*
X656446D03*
X686446D03*
X681446D03*
X676446D03*
X671446D03*
X666446D03*
X655914Y39932D03*
X667149Y23411D03*
X637003Y68809D03*
X648207Y70750D03*
X646643Y97859D03*
X657480Y113385D03*
X678189Y108784D03*
X689049Y109487D03*
X669500Y108400D03*
X692126Y141732D03*
X698425D03*
X679527Y148031D03*
X685826D03*
X692126D03*
X698425D03*
X679527Y154330D03*
X685826D03*
X692126D03*
X698425D03*
Y160629D03*
X692126D03*
X685826D03*
X679527D03*
X698425Y166929D03*
X692126D03*
X685826D03*
X679527D03*
X698425Y173228D03*
X692126D03*
X685826D03*
X666929Y129134D03*
X686352Y207200D03*
X660115Y351977D03*
Y356777D03*
X664731Y343299D03*
X655500Y360000D03*
X660115Y361577D03*
X664731Y338499D03*
Y333699D03*
Y328899D03*
X659977Y342282D03*
Y332682D03*
Y347082D03*
Y337482D03*
Y327882D03*
X696900Y337800D03*
X697500Y358200D03*
X674700Y306300D03*
X679500D03*
Y311100D03*
X674700D03*
X679500Y315900D03*
X674700D03*
X662306Y365477D03*
X657673Y365400D03*
X672281Y378883D03*
X637550Y389050D03*
X653200Y408800D03*
X675700Y468000D03*
Y463500D03*
X675400Y472300D03*
X681540Y429640D03*
X758267Y48426D03*
X744094D03*
X729921D03*
X715748D03*
X758267Y34252D03*
X744094D03*
X729921D03*
X715748D03*
X758267Y20079D03*
X744094D03*
X729921D03*
X715748D03*
X758267Y5906D03*
X744094D03*
X729921D03*
X715748D03*
X751181Y53150D03*
X737007D03*
X722834D03*
X708661D03*
X751181Y38977D03*
X737007D03*
X722834D03*
X708661D03*
X751181Y24804D03*
X737007D03*
X722834D03*
X708661D03*
X701446Y6545D03*
X728788Y88540D03*
X725295Y88609D03*
X752853Y100900D03*
X699563Y108815D03*
X711023Y132283D03*
X717322Y129133D03*
X711023Y122834D03*
X717322D03*
X723622D03*
X743452Y151815D03*
X758050Y164050D03*
X720472Y135433D03*
X704724Y148031D03*
Y154330D03*
Y160629D03*
Y166929D03*
Y173228D03*
X743200Y227900D03*
X706500Y337800D03*
X701700D03*
X707100Y358200D03*
X702300D03*
X722100Y368300D03*
X717300D03*
X712500D03*
X722100Y363500D03*
X717300D03*
X712500D03*
X721380Y423930D03*
X710200Y441200D03*
X821272Y49340D03*
Y44340D03*
Y39340D03*
Y34340D03*
Y29340D03*
Y24340D03*
Y19340D03*
Y14340D03*
Y9340D03*
X815364Y5500D03*
X810364D03*
X805364D03*
X800364D03*
X795364D03*
X790364D03*
X785364D03*
X780364D03*
X775364D03*
X770364D03*
X765364D03*
X799250Y71125D03*
X821272Y114340D03*
Y109340D03*
Y104340D03*
Y99340D03*
Y94340D03*
Y89340D03*
Y84340D03*
Y79340D03*
Y74340D03*
Y69340D03*
Y64340D03*
Y59340D03*
Y54340D03*
X772107Y83046D03*
X799493Y93250D03*
X821272Y174340D03*
Y169340D03*
Y164340D03*
Y159340D03*
Y154340D03*
Y149340D03*
Y144340D03*
Y139340D03*
Y134340D03*
Y129340D03*
Y124340D03*
Y119340D03*
X782500Y134283D03*
X773000Y119600D03*
X776600D03*
X794500Y134283D03*
X785000Y158900D03*
X760600Y173700D03*
X821272Y234340D03*
Y229340D03*
Y224340D03*
Y219340D03*
Y214340D03*
Y209340D03*
Y204340D03*
Y199340D03*
Y194340D03*
Y189340D03*
Y184340D03*
Y179340D03*
X790000Y224700D03*
X795498Y246171D03*
X821272Y299340D03*
Y294340D03*
Y289340D03*
Y284340D03*
Y279340D03*
Y274340D03*
Y269340D03*
Y264340D03*
Y259340D03*
Y254340D03*
Y249340D03*
Y244340D03*
Y239340D03*
X793912Y297020D03*
X793837Y283696D03*
X821272Y359340D03*
Y354340D03*
Y349340D03*
Y344340D03*
Y339340D03*
Y334340D03*
Y329340D03*
Y324340D03*
Y319340D03*
Y314340D03*
Y309340D03*
Y304340D03*
X782770Y321200D03*
X821272Y404340D03*
Y399340D03*
Y394340D03*
Y389340D03*
Y384340D03*
Y379340D03*
Y374340D03*
Y369340D03*
Y364340D03*
G54D26*
X145900Y136500D03*
X632750Y334300D03*
X679527Y173229D03*
X804412Y185332D03*
X800612Y185432D03*
G54D27*
X142865Y424021D03*
X143608Y415900D03*
X145392Y445207D03*
X145456Y440338D03*
X142991Y430900D03*
X381103Y10651D03*
X366929D03*
X352756D03*
X338583D03*
X437796D03*
X423622D03*
X409449D03*
X395276D03*
X425196Y228347D03*
X508661Y10651D03*
X494488D03*
X480315D03*
X466142D03*
X451969D03*
X565354D03*
X551181D03*
X537008D03*
X522835D03*
X579527D03*
X618300Y327654D03*
X673229Y170079D03*
X682675Y132281D03*
X688974D03*
X751181Y10651D03*
X737007D03*
X722834D03*
X708661D03*
G54D19*
X37402Y535158D03*
X789370D03*
G54D20*
X116063Y14567D03*
G54D10*
X15812Y-86244D03*
X27058Y25484D03*
X81539Y542850D03*
X411652Y539991D03*
X812711Y-86834D03*
X798456Y26432D03*
G54D31*
X389764Y460630D03*
X437008D03*
G54D21*
X116063Y39075D03*
G54D30*
X374015Y156220D03*
X531496Y371299D03*
X596456Y116142D03*
X781496Y198818D03*
G54D17*
X37402Y517441D03*
X789370D03*
G54D28*
X295275Y531496D03*
X531495D03*
G54D12*
X75119Y111166D03*
X105619D03*
X81119D03*
X87619D03*
X93619D03*
X99619D03*
X83232Y399956D03*
X229000Y95000D03*
X500000Y311025D03*
X594292Y362291D03*
X625000Y361700D03*
X574667Y479799D03*
X714600Y338900D03*
Y348500D03*
Y343700D03*
X709800Y348500D03*
Y343700D03*
X728700Y381000D03*
Y376200D03*
Y371400D03*
X760715Y210200D03*
Y201700D03*
Y214200D03*
X781640Y278660D03*
G54D13*
X22550Y156750D03*
X52400Y237800D03*
X28455Y187767D03*
X28749Y191548D03*
X39301Y203166D03*
X33700Y230600D03*
X296385Y108227D03*
X325629Y443510D03*
X464568Y275592D03*
X460631Y295277D03*
X462450Y358960D03*
X547379Y338352D03*
X539900Y338300D03*
X534000Y338400D03*
X629813Y27661D03*
X594025Y284017D03*
X610750Y336850D03*
X594050Y301755D03*
X590350Y323011D03*
X656450Y28000D03*
X678700Y440950D03*
G54D33*
X437007Y267718D03*
X448818Y255906D03*
Y263780D03*
Y271655D03*
X440944Y263780D03*
Y271655D03*
X437007Y259843D03*
X440944Y255906D03*
X460630Y275592D03*
X452756D03*
X464567Y255906D03*
Y263780D03*
X456693D03*
X464567Y271655D03*
X456693D03*
G54D34*
X437007Y255905D03*
G54D37*
X632750Y330854D03*
X632900Y344950D03*
X608500Y315000D03*
X676376Y132281D03*
G54D36*
X590537Y170119D03*
X586912Y154495D03*
X584314Y166721D03*
X596233Y145667D03*
X593635Y157893D03*
X588901Y134308D03*
X586303Y146534D03*
X589966Y210195D03*
X587368Y222421D03*
X585841Y194571D03*
X583243Y206797D03*
X581716Y178947D03*
X579118Y191173D03*
X587939Y182345D03*
%LPC*%
G75*
G54D38*
G01X-34018Y-300855D02*
G02I-12000J0D01*
G01X-39168D02*
G02I-6850J0D01*
G01X-30018D02*
X-62018D01*
G01X-30018Y-316855D02*
Y-396855D01*
G01D02*
X1320682D01*
G01X-30018Y-352355D02*
X1320682D01*
G01X-46018Y-316855D02*
Y-284855D01*
G01X-30018Y-316855D02*
X1320682D01*
G01X533182D02*
Y-396855D01*
G01X670682Y-316855D02*
Y-396855D01*
G01X785682Y-316855D02*
Y-396855D01*
G01X953182Y-316855D02*
Y-396855D01*
G01X1123182Y-316855D02*
Y-396855D01*
G01X1320682Y-316855D02*
Y-396855D01*
G01X1348682Y-300855D02*
G02I-12000J0D01*
G01X1343532D02*
G02I-6850J0D01*
G01X1336682Y-316855D02*
Y-284855D01*
G01X1352682Y-300855D02*
X1320682D01*
G54D39*
G01X121778Y-377522D02*
X122652Y-376647D01*
X123307Y-375189D01*
X123744Y-373146D01*
X123307Y-371397D01*
X122434Y-370230D01*
X120905Y-369355D01*
X115010D01*
Y-386855D01*
X122215D01*
X123744Y-385689D01*
X124617Y-383938D01*
X125054Y-381897D01*
X124617Y-379855D01*
X123307Y-378105D01*
X121778Y-377522D01*
X115010D01*
G01X134475Y-386855D02*
Y-375189D01*
G01Y-377522D02*
X135567Y-376355D01*
X136659Y-375480D01*
X138187Y-375189D01*
X139278Y-375480D01*
X140589Y-376355D01*
G01X150447Y-392105D02*
X151757Y-392688D01*
X153504Y-392105D01*
X154595Y-390939D01*
X155469Y-389480D01*
X156778Y-384814D01*
X159617Y-375189D01*
G01X152630D02*
X156778Y-384814D01*
G01X176025Y-376647D02*
X174497Y-375480D01*
X173187Y-375189D01*
X171440Y-375772D01*
X170130Y-376938D01*
X169257Y-378980D01*
X169038Y-381022D01*
X169257Y-383064D01*
X170130Y-384814D01*
X171440Y-386272D01*
X173187Y-386855D01*
X174715Y-386272D01*
X176025Y-385105D01*
G01X186757Y-378980D02*
X193744D01*
X193089Y-376938D01*
X191997Y-375772D01*
X190469Y-375189D01*
X188940Y-375480D01*
X187630Y-376355D01*
X186757Y-378397D01*
X186320Y-380147D01*
Y-381897D01*
X186757Y-383647D01*
X187849Y-385397D01*
X189159Y-386563D01*
X190687Y-386855D01*
X192215Y-386272D01*
X193744Y-384522D01*
G01X229835Y-370814D02*
X228525Y-369938D01*
X226997Y-369355D01*
X225250D01*
X223285Y-370230D01*
X221757Y-371688D01*
X220665Y-373439D01*
X219792Y-376355D01*
X219573Y-378980D01*
X220010Y-381605D01*
X220665Y-383355D01*
X221975Y-385105D01*
X223504Y-386272D01*
X225032Y-386855D01*
X226560D01*
X228089Y-386272D01*
X229399Y-385397D01*
X230491Y-384231D01*
G01X246462Y-386855D02*
Y-375189D01*
G01Y-377230D02*
X245589Y-376064D01*
X244278Y-375480D01*
X242750Y-375189D01*
X241222Y-375772D01*
X239912Y-376938D01*
X239038Y-378688D01*
X238602Y-381022D01*
X239038Y-383355D01*
X239912Y-385105D01*
X241222Y-386272D01*
X242750Y-386855D01*
X244278Y-386563D01*
X245589Y-385689D01*
X246462Y-384522D01*
G01X256320Y-386855D02*
Y-375189D01*
G01Y-378105D02*
X257194Y-376647D01*
X258504Y-375480D01*
X260250Y-375189D01*
X261778Y-375480D01*
X263089Y-376647D01*
X263744Y-378688D01*
Y-386855D01*
G01X272947Y-392105D02*
X274257Y-392688D01*
X276004Y-392105D01*
X277095Y-390939D01*
X277969Y-389480D01*
X279278Y-384814D01*
X282117Y-375189D01*
G01X275130D02*
X279278Y-384814D01*
G01X295032Y-386855D02*
X293722Y-386563D01*
X292412Y-385397D01*
X291538Y-383355D01*
X291102Y-381022D01*
X291538Y-378688D01*
X292412Y-376647D01*
X293722Y-375480D01*
X295032Y-375189D01*
X296342Y-375480D01*
X297652Y-376647D01*
X298525Y-378688D01*
X298744Y-381022D01*
X298525Y-383355D01*
X297652Y-385397D01*
X296342Y-386563D01*
X295032Y-386855D01*
G01X308820D02*
Y-375189D01*
G01Y-378105D02*
X309694Y-376647D01*
X311004Y-375480D01*
X312750Y-375189D01*
X314278Y-375480D01*
X315589Y-376647D01*
X316244Y-378688D01*
Y-386855D01*
G01X342947Y-384522D02*
X344694Y-385980D01*
X346659Y-386855D01*
X348405D01*
X350152Y-385980D01*
X351462Y-384522D01*
X352117Y-382480D01*
X351680Y-380439D01*
X350589Y-378688D01*
X348624Y-377522D01*
X346004Y-376938D01*
X344475Y-375772D01*
X343820Y-373730D01*
X344257Y-371688D01*
X345349Y-370230D01*
X346877Y-369355D01*
X348405D01*
X349934Y-369938D01*
X351244Y-371397D01*
G01X369835Y-370814D02*
X368525Y-369938D01*
X366997Y-369355D01*
X365250D01*
X363285Y-370230D01*
X361757Y-371688D01*
X360665Y-373439D01*
X359792Y-376355D01*
X359573Y-378980D01*
X360010Y-381605D01*
X360665Y-383355D01*
X361975Y-385105D01*
X363504Y-386272D01*
X365032Y-386855D01*
X366560D01*
X368089Y-386272D01*
X369399Y-385397D01*
X370491Y-384231D01*
G01X387335Y-370814D02*
X386025Y-369938D01*
X384497Y-369355D01*
X382750D01*
X380785Y-370230D01*
X379257Y-371688D01*
X378165Y-373439D01*
X377292Y-376355D01*
X377073Y-378980D01*
X377510Y-381605D01*
X378165Y-383355D01*
X379475Y-385105D01*
X381004Y-386272D01*
X382532Y-386855D01*
X384060D01*
X385589Y-386272D01*
X386899Y-385397D01*
X387991Y-384231D01*
G01X210605Y-341855D02*
Y-324355D01*
X216282Y-338938D01*
X221959Y-324355D01*
Y-341855D01*
G01X233782D02*
X232472Y-341563D01*
X231162Y-340397D01*
X230288Y-338355D01*
X229852Y-336022D01*
X230288Y-333688D01*
X231162Y-331647D01*
X232472Y-330480D01*
X233782Y-330189D01*
X235092Y-330480D01*
X236402Y-331647D01*
X237275Y-333688D01*
X237494Y-336022D01*
X237275Y-338355D01*
X236402Y-340397D01*
X235092Y-341563D01*
X233782Y-341855D01*
G01X255212Y-324355D02*
Y-341855D01*
G01Y-339231D02*
X254339Y-340689D01*
X253028Y-341563D01*
X251500Y-341855D01*
X249754Y-341272D01*
X248444Y-339814D01*
X247570Y-338064D01*
X247352Y-336022D01*
X247570Y-333980D01*
X248444Y-332230D01*
X249754Y-330772D01*
X251500Y-330189D01*
X253028Y-330480D01*
X254120Y-331064D01*
X255212Y-332230D01*
G01X265507Y-333980D02*
X272494D01*
X271839Y-331938D01*
X270747Y-330772D01*
X269219Y-330189D01*
X267690Y-330480D01*
X266380Y-331355D01*
X265507Y-333397D01*
X265070Y-335147D01*
Y-336897D01*
X265507Y-338647D01*
X266599Y-340397D01*
X267909Y-341563D01*
X269437Y-341855D01*
X270965Y-341272D01*
X272494Y-339522D01*
G01X286282Y-341855D02*
Y-324355D01*
G01X566882Y-386855D02*
Y-369355D01*
X564262Y-372855D01*
G01Y-386855D02*
X569502D01*
G01X580234Y-379564D02*
X581762Y-377522D01*
X583072Y-376355D01*
X584819Y-375772D01*
X586347Y-376355D01*
X587439Y-377522D01*
X588312Y-379272D01*
X588530Y-381313D01*
X588312Y-383064D01*
X587439Y-384814D01*
X586128Y-386272D01*
X584600Y-386855D01*
X582854Y-386272D01*
X581325Y-384522D01*
X580452Y-381897D01*
X580234Y-378980D01*
X580670Y-375189D01*
X581325Y-373146D01*
X582417Y-371105D01*
X583945Y-369647D01*
X585474Y-369355D01*
X587002Y-369938D01*
X588094Y-371397D01*
G01X597079Y-383355D02*
X598388Y-385397D01*
X600135Y-386563D01*
X602100Y-386855D01*
X603847Y-386563D01*
X605594Y-385105D01*
X606685Y-383355D01*
X606904Y-381605D01*
X606467Y-379564D01*
X604939Y-378105D01*
X603410Y-377522D01*
X601445D01*
G01X603410D02*
X604720Y-376647D01*
X605812Y-375189D01*
X606249Y-373439D01*
X605812Y-371688D01*
X604720Y-370230D01*
X602755Y-369355D01*
X600790Y-369647D01*
X598825Y-370814D01*
G01X619382Y-386855D02*
Y-369355D01*
X616762Y-372855D01*
G01Y-386855D02*
X622002D01*
G01X632734Y-379564D02*
X634262Y-377522D01*
X635572Y-376355D01*
X637319Y-375772D01*
X638847Y-376355D01*
X639939Y-377522D01*
X640812Y-379272D01*
X641030Y-381313D01*
X640812Y-383064D01*
X639939Y-384814D01*
X638628Y-386272D01*
X637100Y-386855D01*
X635354Y-386272D01*
X633825Y-384522D01*
X632952Y-381897D01*
X632734Y-378980D01*
X633170Y-375189D01*
X633825Y-373146D01*
X634917Y-371105D01*
X636445Y-369647D01*
X637974Y-369355D01*
X639502Y-369938D01*
X640594Y-371397D01*
G01X553765Y-341855D02*
Y-324355D01*
X559005D01*
X560752Y-325230D01*
X562062Y-327272D01*
X562499Y-329605D01*
X562062Y-331938D01*
X560970Y-333688D01*
X559005Y-334564D01*
X553765D01*
G01X580435Y-325814D02*
X579125Y-324938D01*
X577597Y-324355D01*
X575850D01*
X573885Y-325230D01*
X572357Y-326688D01*
X571265Y-328439D01*
X570392Y-331355D01*
X570173Y-333980D01*
X570610Y-336605D01*
X571265Y-338355D01*
X572575Y-340105D01*
X574104Y-341272D01*
X575632Y-341855D01*
X577160D01*
X578689Y-341272D01*
X579999Y-340397D01*
X581091Y-339231D01*
G01X594878Y-332522D02*
X595752Y-331647D01*
X596407Y-330189D01*
X596844Y-328146D01*
X596407Y-326397D01*
X595534Y-325230D01*
X594005Y-324355D01*
X588110D01*
Y-341855D01*
X595315D01*
X596844Y-340689D01*
X597717Y-338938D01*
X598154Y-336897D01*
X597717Y-334855D01*
X596407Y-333105D01*
X594878Y-332522D01*
X588110D01*
G01X604082Y-347688D02*
X617182D01*
G01X623110Y-341855D02*
Y-324355D01*
X633154Y-341855D01*
Y-324355D01*
G01X645632Y-341855D02*
X643885Y-341563D01*
X642357Y-340397D01*
X641047Y-338647D01*
X640173Y-336605D01*
X639737Y-334272D01*
Y-331938D01*
X640173Y-329605D01*
X641047Y-327563D01*
X642357Y-325814D01*
X643885Y-324647D01*
X645632Y-324355D01*
X647378Y-324647D01*
X648907Y-325814D01*
X650217Y-327563D01*
X651091Y-329605D01*
X651527Y-331938D01*
Y-334272D01*
X651091Y-336605D01*
X650217Y-338647D01*
X648907Y-340397D01*
X647378Y-341563D01*
X645632Y-341855D01*
G01X696473Y-324355D02*
X701932Y-341855D01*
X707391Y-324355D01*
G01X723799Y-341855D02*
X715065D01*
Y-324355D01*
X723799D01*
G01X720305Y-332813D02*
X715065D01*
G01X732565Y-341855D02*
Y-324355D01*
X738024D01*
X739770Y-325230D01*
X740862Y-326397D01*
X741299Y-328730D01*
X740862Y-331064D01*
X739552Y-332522D01*
X738024Y-333397D01*
X732565D01*
G01X738024D02*
X741299Y-341855D01*
G01X754432Y-342438D02*
X753995Y-342147D01*
Y-341563D01*
X754432Y-341272D01*
X754869Y-341563D01*
Y-342147D01*
X754432Y-342438D01*
G01X728182Y-386855D02*
Y-369355D01*
X725562Y-372855D01*
G01Y-386855D02*
X730802D01*
G01X908749Y-369355D02*
Y-386855D01*
X900015D01*
G01X891685Y-384231D02*
X890376Y-385689D01*
X888847Y-386563D01*
X886882Y-386855D01*
X884917Y-386272D01*
X883389Y-385105D01*
X882297Y-383064D01*
X882079Y-380730D01*
X882515Y-378397D01*
X883607Y-376938D01*
X885136Y-375772D01*
X886664Y-375480D01*
X888192Y-375772D01*
X890157Y-376938D01*
X889502Y-369355D01*
X883607D01*
G01X874841D02*
X869382Y-386855D01*
X863923Y-369355D01*
G01X847079Y-370814D02*
X848389Y-369938D01*
X849917Y-369355D01*
X851664D01*
X853629Y-370230D01*
X855157Y-371688D01*
X856249Y-373439D01*
X857122Y-376355D01*
X857341Y-378980D01*
X856904Y-381605D01*
X856249Y-383355D01*
X854939Y-385105D01*
X853410Y-386272D01*
X851882Y-386855D01*
X850354D01*
X848825Y-386272D01*
X847515Y-385397D01*
X846423Y-384231D01*
G01X829579Y-370814D02*
X830889Y-369938D01*
X832417Y-369355D01*
X834164D01*
X836129Y-370230D01*
X837657Y-371688D01*
X838749Y-373439D01*
X839622Y-376355D01*
X839841Y-378980D01*
X839404Y-381605D01*
X838749Y-383355D01*
X837439Y-385105D01*
X835910Y-386272D01*
X834382Y-386855D01*
X832854D01*
X831325Y-386272D01*
X830015Y-385397D01*
X828923Y-384231D01*
G01X830015Y-324355D02*
Y-341855D01*
X838749D01*
G01X855812D02*
Y-330189D01*
G01Y-332230D02*
X854939Y-331064D01*
X853628Y-330480D01*
X852100Y-330189D01*
X850572Y-330772D01*
X849262Y-331938D01*
X848388Y-333688D01*
X847952Y-336022D01*
X848388Y-338355D01*
X849262Y-340105D01*
X850572Y-341272D01*
X852100Y-341855D01*
X853628Y-341563D01*
X854939Y-340689D01*
X855812Y-339522D01*
G01X864797Y-347105D02*
X866107Y-347688D01*
X867854Y-347105D01*
X868945Y-345939D01*
X869819Y-344480D01*
X871128Y-339814D01*
X873967Y-330189D01*
G01X866980D02*
X871128Y-339814D01*
G01X883607Y-333980D02*
X890594D01*
X889939Y-331938D01*
X888847Y-330772D01*
X887319Y-330189D01*
X885790Y-330480D01*
X884480Y-331355D01*
X883607Y-333397D01*
X883170Y-335147D01*
Y-336897D01*
X883607Y-338647D01*
X884699Y-340397D01*
X886009Y-341563D01*
X887537Y-341855D01*
X889065Y-341272D01*
X890594Y-339522D01*
G01X901325Y-341855D02*
Y-330189D01*
G01Y-332522D02*
X902417Y-331355D01*
X903509Y-330480D01*
X905037Y-330189D01*
X906128Y-330480D01*
X907439Y-331355D01*
G01X994432Y-386855D02*
X992685Y-386563D01*
X991157Y-385397D01*
X989847Y-383647D01*
X988973Y-381605D01*
X988537Y-379272D01*
Y-376938D01*
X988973Y-374605D01*
X989847Y-372563D01*
X991157Y-370814D01*
X992685Y-369647D01*
X994432Y-369355D01*
X996178Y-369647D01*
X997707Y-370814D01*
X999017Y-372563D01*
X999891Y-374605D01*
X1000327Y-376938D01*
Y-379272D01*
X999891Y-381605D01*
X999017Y-383647D01*
X997707Y-385397D01*
X996178Y-386563D01*
X994432Y-386855D01*
G01X996178Y-382188D02*
X998799Y-386855D01*
G01X1007129Y-369355D02*
Y-381897D01*
X1008002Y-384522D01*
X1009749Y-386272D01*
X1011932Y-386855D01*
X1014115Y-386272D01*
X1015862Y-384522D01*
X1016735Y-381897D01*
Y-369355D01*
G01X1026812D02*
X1032052D01*
G01X1029432D02*
Y-386855D01*
G01X1026812D02*
X1032052D01*
G01X1041910D02*
Y-369355D01*
X1051954Y-386855D01*
Y-369355D01*
G01X1069235Y-370814D02*
X1067925Y-369938D01*
X1066397Y-369355D01*
X1064650D01*
X1062685Y-370230D01*
X1061157Y-371688D01*
X1060065Y-373439D01*
X1059192Y-376355D01*
X1058973Y-378980D01*
X1059410Y-381605D01*
X1060065Y-383355D01*
X1061375Y-385105D01*
X1062904Y-386272D01*
X1064432Y-386855D01*
X1065960D01*
X1067489Y-386272D01*
X1068799Y-385397D01*
X1069891Y-384231D01*
G01X1081932Y-386855D02*
Y-378980D01*
X1077565Y-369355D01*
G01X1086299D02*
X1081932Y-378980D01*
G01X972129Y-341855D02*
Y-324355D01*
X976495D01*
X978242Y-325230D01*
X979552Y-326397D01*
X980644Y-328146D01*
X981517Y-330189D01*
X981735Y-333105D01*
X981517Y-336022D01*
X980644Y-338064D01*
X979552Y-339814D01*
X978242Y-340980D01*
X976495Y-341855D01*
X972129D01*
G01X991157Y-333980D02*
X998144D01*
X997489Y-331938D01*
X996397Y-330772D01*
X994869Y-330189D01*
X993340Y-330480D01*
X992030Y-331355D01*
X991157Y-333397D01*
X990720Y-335147D01*
Y-336897D01*
X991157Y-338647D01*
X992249Y-340397D01*
X993559Y-341563D01*
X995087Y-341855D01*
X996615Y-341272D01*
X998144Y-339522D01*
G01X1008657Y-339814D02*
X1009749Y-340980D01*
X1011277Y-341855D01*
X1012587D01*
X1013897Y-341272D01*
X1014770Y-340397D01*
X1015207Y-339231D01*
X1014989Y-337480D01*
X1014115Y-336605D01*
X1010185Y-334855D01*
X1009312Y-332813D01*
X1009749Y-331355D01*
X1010622Y-330480D01*
X1011932Y-330189D01*
X1013242Y-330480D01*
X1014552Y-331355D01*
G01X1029432Y-330189D02*
Y-341855D01*
G01Y-325522D02*
X1028995Y-325230D01*
Y-324647D01*
X1029432Y-324355D01*
X1029869Y-324647D01*
Y-325230D01*
X1029432Y-325522D01*
G01X1043875Y-346230D02*
X1045404Y-347397D01*
X1047150Y-347688D01*
X1048678Y-347397D01*
X1049989Y-345939D01*
X1050862Y-343897D01*
Y-330189D01*
G01Y-332522D02*
X1049989Y-331355D01*
X1048678Y-330480D01*
X1047150Y-330189D01*
X1045404Y-330772D01*
X1044312Y-331938D01*
X1043438Y-333980D01*
X1043002Y-336022D01*
X1043220Y-337772D01*
X1044094Y-339814D01*
X1045404Y-341272D01*
X1047150Y-341855D01*
X1048460Y-341563D01*
X1049989Y-340397D01*
X1050862Y-339231D01*
G01X1060720Y-341855D02*
Y-330189D01*
G01Y-333105D02*
X1061594Y-331647D01*
X1062904Y-330480D01*
X1064650Y-330189D01*
X1066178Y-330480D01*
X1067489Y-331647D01*
X1068144Y-333688D01*
Y-341855D01*
G01X1078657Y-333980D02*
X1085644D01*
X1084989Y-331938D01*
X1083897Y-330772D01*
X1082369Y-330189D01*
X1080840Y-330480D01*
X1079530Y-331355D01*
X1078657Y-333397D01*
X1078220Y-335147D01*
Y-336897D01*
X1078657Y-338647D01*
X1079749Y-340397D01*
X1081059Y-341563D01*
X1082587Y-341855D01*
X1084115Y-341272D01*
X1085644Y-339522D01*
G01X1096375Y-341855D02*
Y-330189D01*
G01Y-332522D02*
X1097467Y-331355D01*
X1098559Y-330480D01*
X1100087Y-330189D01*
X1101178Y-330480D01*
X1102489Y-331355D01*
G01X1143132Y-369355D02*
X1141385Y-369938D01*
X1140075Y-371397D01*
X1139202Y-373146D01*
X1138547Y-375480D01*
X1138329Y-378105D01*
X1138547Y-380730D01*
X1139202Y-383064D01*
X1140075Y-384814D01*
X1141385Y-386272D01*
X1143132Y-386855D01*
X1144878Y-386272D01*
X1146189Y-384814D01*
X1147062Y-383064D01*
X1147717Y-380730D01*
X1147935Y-378105D01*
X1147717Y-375480D01*
X1147062Y-373146D01*
X1146189Y-371397D01*
X1144878Y-369938D01*
X1143132Y-369355D01*
G01X1156484Y-379564D02*
X1158012Y-377522D01*
X1159322Y-376355D01*
X1161069Y-375772D01*
X1162597Y-376355D01*
X1163689Y-377522D01*
X1164562Y-379272D01*
X1164780Y-381313D01*
X1164562Y-383064D01*
X1163689Y-384814D01*
X1162378Y-386272D01*
X1160850Y-386855D01*
X1159104Y-386272D01*
X1157575Y-384522D01*
X1156702Y-381897D01*
X1156484Y-378980D01*
X1156920Y-375189D01*
X1157575Y-373146D01*
X1158667Y-371105D01*
X1160195Y-369647D01*
X1161724Y-369355D01*
X1163252Y-369938D01*
X1164344Y-371397D01*
G01X1174202Y-387438D02*
X1182062Y-369355D01*
G01X1191484Y-372272D02*
X1192794Y-370522D01*
X1194322Y-369647D01*
X1196069Y-369355D01*
X1198252Y-369938D01*
X1199780Y-371397D01*
X1200217Y-373146D01*
X1199999Y-374897D01*
X1199125Y-376355D01*
X1194759Y-379272D01*
X1192794Y-381313D01*
X1191484Y-384231D01*
X1191047Y-386855D01*
X1200217D01*
G01X1213132D02*
Y-369355D01*
X1210512Y-372855D01*
G01Y-386855D02*
X1215752D01*
G01X1226702Y-387438D02*
X1234562Y-369355D01*
G01X1243984Y-372272D02*
X1245294Y-370522D01*
X1246822Y-369647D01*
X1248569Y-369355D01*
X1250752Y-369938D01*
X1252280Y-371397D01*
X1252717Y-373146D01*
X1252499Y-374897D01*
X1251625Y-376355D01*
X1247259Y-379272D01*
X1245294Y-381313D01*
X1243984Y-384231D01*
X1243547Y-386855D01*
X1252717D01*
G01X1265632Y-369355D02*
X1263885Y-369938D01*
X1262575Y-371397D01*
X1261702Y-373146D01*
X1261047Y-375480D01*
X1260829Y-378105D01*
X1261047Y-380730D01*
X1261702Y-383064D01*
X1262575Y-384814D01*
X1263885Y-386272D01*
X1265632Y-386855D01*
X1267378Y-386272D01*
X1268689Y-384814D01*
X1269562Y-383064D01*
X1270217Y-380730D01*
X1270435Y-378105D01*
X1270217Y-375480D01*
X1269562Y-373146D01*
X1268689Y-371397D01*
X1267378Y-369938D01*
X1265632Y-369355D01*
G01X1283132Y-386855D02*
Y-369355D01*
X1280512Y-372855D01*
G01Y-386855D02*
X1285752D01*
G01X1300195D02*
X1300632Y-383064D01*
X1301287Y-379855D01*
X1302160Y-376938D01*
X1303252Y-373730D01*
X1304999Y-369355D01*
X1296265D01*
G01X1190829Y-341855D02*
Y-324355D01*
X1195195D01*
X1196942Y-325230D01*
X1198252Y-326397D01*
X1199344Y-328146D01*
X1200217Y-330189D01*
X1200435Y-333105D01*
X1200217Y-336022D01*
X1199344Y-338064D01*
X1198252Y-339814D01*
X1196942Y-340980D01*
X1195195Y-341855D01*
X1190829D01*
G01X1217062D02*
Y-330189D01*
G01Y-332230D02*
X1216189Y-331064D01*
X1214878Y-330480D01*
X1213350Y-330189D01*
X1211822Y-330772D01*
X1210512Y-331938D01*
X1209638Y-333688D01*
X1209202Y-336022D01*
X1209638Y-338355D01*
X1210512Y-340105D01*
X1211822Y-341272D01*
X1213350Y-341855D01*
X1214878Y-341563D01*
X1216189Y-340689D01*
X1217062Y-339522D01*
G01X1230632Y-324355D02*
Y-341855D01*
G01X1227575Y-330189D02*
X1233689D01*
G01X1244857Y-333980D02*
X1251844D01*
X1251189Y-331938D01*
X1250097Y-330772D01*
X1248569Y-330189D01*
X1247040Y-330480D01*
X1245730Y-331355D01*
X1244857Y-333397D01*
X1244420Y-335147D01*
Y-336897D01*
X1244857Y-338647D01*
X1245949Y-340397D01*
X1247259Y-341563D01*
X1248787Y-341855D01*
X1250315Y-341272D01*
X1251844Y-339522D01*
M02*
